G04*
G04 #@! TF.GenerationSoftware,Altium Limited,Altium Designer,22.4.2 (48)*
G04*
G04 Layer_Color=8388736*
%FSLAX25Y25*%
%MOIN*%
G70*
G04*
G04 #@! TF.SameCoordinates,446674BB-F454-490D-8607-5140536C8ADF*
G04*
G04*
G04 #@! TF.FilePolarity,Positive*
G04*
G01*
G75*
%ADD13C,0.00787*%
G36*
X672835Y-223231D02*
X672831D01*
X672817D01*
X672795D01*
X672765Y-223228D01*
X672733Y-223224D01*
X672696Y-223217D01*
X672660Y-223209D01*
X672620Y-223195D01*
X672616D01*
X672613Y-223191D01*
X672591Y-223184D01*
X672558Y-223169D01*
X672514Y-223147D01*
X672463Y-223118D01*
X672405Y-223082D01*
X672347Y-223042D01*
X672285Y-222991D01*
X672281D01*
X672278Y-222984D01*
X672256Y-222965D01*
X672223Y-222933D01*
X672176Y-222885D01*
X672121Y-222831D01*
X672056Y-222762D01*
X671983Y-222678D01*
X671907Y-222587D01*
X671903Y-222583D01*
X671892Y-222569D01*
X671874Y-222547D01*
X671852Y-222521D01*
X671823Y-222489D01*
X671790Y-222448D01*
X671754Y-222409D01*
X671714Y-222361D01*
X671626Y-222270D01*
X671539Y-222179D01*
X671495Y-222135D01*
X671452Y-222095D01*
X671411Y-222059D01*
X671371Y-222030D01*
X671368D01*
X671364Y-222023D01*
X671353Y-222015D01*
X671339Y-222008D01*
X671299Y-221983D01*
X671251Y-221954D01*
X671193Y-221928D01*
X671131Y-221903D01*
X671062Y-221888D01*
X670997Y-221881D01*
X670993D01*
X670989D01*
X670967Y-221884D01*
X670931Y-221888D01*
X670891Y-221899D01*
X670840Y-221914D01*
X670789Y-221939D01*
X670738Y-221972D01*
X670687Y-222015D01*
X670680Y-222023D01*
X670665Y-222041D01*
X670647Y-222066D01*
X670622Y-222106D01*
X670600Y-222157D01*
X670578Y-222216D01*
X670563Y-222285D01*
X670560Y-222361D01*
Y-222383D01*
X670563Y-222398D01*
X670567Y-222441D01*
X670578Y-222492D01*
X670592Y-222547D01*
X670618Y-222609D01*
X670651Y-222667D01*
X670694Y-222722D01*
X670702Y-222729D01*
X670720Y-222743D01*
X670749Y-222765D01*
X670793Y-222787D01*
X670844Y-222813D01*
X670909Y-222834D01*
X670982Y-222849D01*
X671066Y-222856D01*
X671033Y-223173D01*
X671029D01*
X671018Y-223169D01*
X671000D01*
X670975Y-223166D01*
X670946Y-223158D01*
X670913Y-223151D01*
X670873Y-223140D01*
X670833Y-223129D01*
X670745Y-223100D01*
X670658Y-223056D01*
X670614Y-223031D01*
X670571Y-222998D01*
X670531Y-222965D01*
X670494Y-222929D01*
X670491Y-222925D01*
X670487Y-222918D01*
X670476Y-222907D01*
X670465Y-222889D01*
X670450Y-222867D01*
X670436Y-222842D01*
X670418Y-222813D01*
X670400Y-222776D01*
X670381Y-222736D01*
X670363Y-222692D01*
X670349Y-222645D01*
X670334Y-222594D01*
X670323Y-222540D01*
X670312Y-222481D01*
X670308Y-222419D01*
X670305Y-222354D01*
Y-222318D01*
X670308Y-222292D01*
X670312Y-222263D01*
X670316Y-222227D01*
X670323Y-222186D01*
X670330Y-222146D01*
X670356Y-222052D01*
X670392Y-221957D01*
X670414Y-221910D01*
X670440Y-221863D01*
X670472Y-221819D01*
X670509Y-221779D01*
X670512Y-221775D01*
X670516Y-221768D01*
X670531Y-221761D01*
X670545Y-221746D01*
X670563Y-221728D01*
X670589Y-221710D01*
X670614Y-221691D01*
X670647Y-221670D01*
X670716Y-221633D01*
X670804Y-221597D01*
X670847Y-221582D01*
X670898Y-221575D01*
X670949Y-221568D01*
X671004Y-221564D01*
X671011D01*
X671029D01*
X671058Y-221568D01*
X671098Y-221571D01*
X671142Y-221579D01*
X671193Y-221593D01*
X671248Y-221608D01*
X671302Y-221630D01*
X671310Y-221633D01*
X671328Y-221640D01*
X671357Y-221655D01*
X671397Y-221677D01*
X671441Y-221706D01*
X671495Y-221742D01*
X671550Y-221786D01*
X671612Y-221837D01*
X671619Y-221844D01*
X671641Y-221863D01*
X671659Y-221881D01*
X671677Y-221899D01*
X671699Y-221921D01*
X671728Y-221950D01*
X671757Y-221979D01*
X671790Y-222015D01*
X671826Y-222052D01*
X671866Y-222095D01*
X671907Y-222143D01*
X671954Y-222194D01*
X672001Y-222252D01*
X672052Y-222310D01*
X672056Y-222314D01*
X672063Y-222321D01*
X672074Y-222336D01*
X672088Y-222354D01*
X672110Y-222376D01*
X672132Y-222401D01*
X672180Y-222460D01*
X672234Y-222521D01*
X672289Y-222580D01*
X672336Y-222631D01*
X672354Y-222652D01*
X672372Y-222671D01*
X672376Y-222674D01*
X672387Y-222685D01*
X672402Y-222700D01*
X672423Y-222718D01*
X672449Y-222736D01*
X672474Y-222758D01*
X672536Y-222802D01*
Y-221560D01*
X672835D01*
Y-223231D01*
D02*
G37*
G36*
Y-224290D02*
X670865D01*
X670869Y-224294D01*
X670884Y-224312D01*
X670905Y-224334D01*
X670931Y-224371D01*
X670964Y-224411D01*
X671000Y-224462D01*
X671040Y-224520D01*
X671080Y-224585D01*
Y-224589D01*
X671084Y-224592D01*
X671098Y-224614D01*
X671117Y-224651D01*
X671138Y-224694D01*
X671164Y-224745D01*
X671189Y-224800D01*
X671215Y-224855D01*
X671237Y-224909D01*
X670938D01*
Y-224905D01*
X670931Y-224898D01*
X670927Y-224884D01*
X670916Y-224866D01*
X670905Y-224844D01*
X670891Y-224818D01*
X670855Y-224756D01*
X670815Y-224683D01*
X670763Y-224611D01*
X670705Y-224534D01*
X670643Y-224458D01*
X670640Y-224454D01*
X670636Y-224451D01*
X670625Y-224440D01*
X670614Y-224425D01*
X670578Y-224392D01*
X670534Y-224349D01*
X670483Y-224305D01*
X670425Y-224258D01*
X670367Y-224218D01*
X670305Y-224181D01*
Y-223981D01*
X672835D01*
Y-224290D01*
D02*
G37*
G36*
X671637Y-225481D02*
X671666D01*
X671735Y-225484D01*
X671815Y-225495D01*
X671899Y-225506D01*
X671987Y-225524D01*
X672074Y-225546D01*
X672078D01*
X672085Y-225550D01*
X672096Y-225553D01*
X672110Y-225557D01*
X672150Y-225572D01*
X672201Y-225593D01*
X672260Y-225615D01*
X672318Y-225644D01*
X672380Y-225681D01*
X672438Y-225717D01*
X672445Y-225721D01*
X672463Y-225735D01*
X672489Y-225757D01*
X672522Y-225786D01*
X672558Y-225819D01*
X672594Y-225859D01*
X672635Y-225899D01*
X672667Y-225947D01*
X672671Y-225954D01*
X672682Y-225968D01*
X672696Y-225994D01*
X672715Y-226030D01*
X672736Y-226074D01*
X672755Y-226125D01*
X672776Y-226183D01*
X672795Y-226249D01*
Y-226256D01*
X672798Y-226267D01*
X672802Y-226278D01*
X672806Y-226314D01*
X672813Y-226365D01*
X672820Y-226423D01*
X672827Y-226493D01*
X672831Y-226569D01*
X672835Y-226653D01*
Y-227559D01*
X670316D01*
Y-226591D01*
X670319Y-226525D01*
X670323Y-226453D01*
X670330Y-226380D01*
X670341Y-226307D01*
X670352Y-226245D01*
Y-226241D01*
X670356Y-226234D01*
Y-226223D01*
X670363Y-226209D01*
X670374Y-226169D01*
X670392Y-226118D01*
X670418Y-226059D01*
X670450Y-225998D01*
X670487Y-225936D01*
X670534Y-225877D01*
X670538Y-225874D01*
X670541Y-225870D01*
X670552Y-225859D01*
X670563Y-225845D01*
X670600Y-225808D01*
X670651Y-225765D01*
X670713Y-225717D01*
X670785Y-225666D01*
X670869Y-225619D01*
X670964Y-225579D01*
X670967D01*
X670975Y-225575D01*
X670989Y-225568D01*
X671011Y-225564D01*
X671036Y-225553D01*
X671066Y-225546D01*
X671098Y-225539D01*
X671138Y-225528D01*
X671178Y-225517D01*
X671226Y-225510D01*
X671328Y-225492D01*
X671441Y-225481D01*
X671564Y-225477D01*
X671568D01*
X671575D01*
X671593D01*
X671612D01*
X671637Y-225481D01*
D02*
G37*
G36*
X675397Y-277740D02*
X675393Y-277805D01*
X675390Y-277878D01*
X675383Y-277951D01*
X675372Y-278024D01*
X675361Y-278086D01*
Y-278089D01*
X675357Y-278097D01*
Y-278108D01*
X675350Y-278122D01*
X675339Y-278162D01*
X675321Y-278213D01*
X675295Y-278271D01*
X675262Y-278333D01*
X675226Y-278395D01*
X675179Y-278453D01*
X675175Y-278457D01*
X675172Y-278461D01*
X675161Y-278471D01*
X675150Y-278486D01*
X675113Y-278522D01*
X675062Y-278566D01*
X675000Y-278613D01*
X674928Y-278664D01*
X674844Y-278712D01*
X674749Y-278752D01*
X674746D01*
X674738Y-278755D01*
X674724Y-278763D01*
X674702Y-278766D01*
X674677Y-278777D01*
X674647Y-278784D01*
X674615Y-278792D01*
X674575Y-278803D01*
X674535Y-278814D01*
X674487Y-278821D01*
X674385Y-278839D01*
X674272Y-278850D01*
X674149Y-278854D01*
X674145D01*
X674138D01*
X674120D01*
X674101D01*
X674076Y-278850D01*
X674047D01*
X673978Y-278846D01*
X673898Y-278836D01*
X673814Y-278825D01*
X673726Y-278806D01*
X673639Y-278784D01*
X673635D01*
X673628Y-278781D01*
X673617Y-278777D01*
X673603Y-278774D01*
X673563Y-278759D01*
X673512Y-278737D01*
X673453Y-278715D01*
X673395Y-278686D01*
X673333Y-278650D01*
X673275Y-278613D01*
X673268Y-278610D01*
X673250Y-278595D01*
X673224Y-278573D01*
X673191Y-278544D01*
X673155Y-278512D01*
X673118Y-278471D01*
X673078Y-278431D01*
X673046Y-278384D01*
X673042Y-278377D01*
X673031Y-278362D01*
X673017Y-278337D01*
X672998Y-278300D01*
X672977Y-278257D01*
X672958Y-278206D01*
X672936Y-278148D01*
X672918Y-278082D01*
Y-278075D01*
X672915Y-278064D01*
X672911Y-278053D01*
X672907Y-278016D01*
X672900Y-277965D01*
X672893Y-277907D01*
X672886Y-277838D01*
X672882Y-277762D01*
X672878Y-277678D01*
Y-276772D01*
X675397D01*
Y-277740D01*
D02*
G37*
G36*
X674775Y-279425D02*
X674782Y-279433D01*
X674786Y-279447D01*
X674797Y-279465D01*
X674808Y-279487D01*
X674822Y-279513D01*
X674858Y-279574D01*
X674898Y-279647D01*
X674949Y-279720D01*
X675008Y-279797D01*
X675070Y-279873D01*
X675073Y-279876D01*
X675077Y-279880D01*
X675088Y-279891D01*
X675099Y-279906D01*
X675135Y-279938D01*
X675179Y-279982D01*
X675230Y-280026D01*
X675288Y-280073D01*
X675346Y-280113D01*
X675408Y-280150D01*
Y-280350D01*
X672878D01*
Y-280040D01*
X674848D01*
X674844Y-280037D01*
X674829Y-280018D01*
X674808Y-279997D01*
X674782Y-279960D01*
X674749Y-279920D01*
X674713Y-279869D01*
X674673Y-279811D01*
X674633Y-279746D01*
Y-279742D01*
X674629Y-279738D01*
X674615Y-279716D01*
X674596Y-279680D01*
X674575Y-279636D01*
X674549Y-279585D01*
X674524Y-279531D01*
X674498Y-279476D01*
X674476Y-279421D01*
X674775D01*
Y-279425D01*
D02*
G37*
G36*
X674618Y-281147D02*
X674651Y-281151D01*
X674691Y-281154D01*
X674731Y-281161D01*
X674778Y-281172D01*
X674873Y-281198D01*
X674924Y-281216D01*
X674979Y-281238D01*
X675030Y-281263D01*
X675077Y-281296D01*
X675128Y-281329D01*
X675172Y-281369D01*
X675175Y-281373D01*
X675182Y-281380D01*
X675193Y-281391D01*
X675208Y-281409D01*
X675226Y-281431D01*
X675248Y-281460D01*
X675266Y-281489D01*
X675292Y-281525D01*
X675314Y-281562D01*
X675332Y-281606D01*
X675372Y-281704D01*
X675386Y-281755D01*
X675397Y-281813D01*
X675404Y-281871D01*
X675408Y-281933D01*
Y-281959D01*
X675404Y-281977D01*
Y-281995D01*
X675401Y-282020D01*
X675390Y-282082D01*
X675375Y-282152D01*
X675350Y-282228D01*
X675317Y-282304D01*
X675273Y-282381D01*
Y-282384D01*
X675266Y-282388D01*
X675259Y-282399D01*
X675248Y-282414D01*
X675219Y-282450D01*
X675179Y-282497D01*
X675124Y-282545D01*
X675059Y-282599D01*
X674982Y-282647D01*
X674895Y-282690D01*
X674891D01*
X674884Y-282694D01*
X674869Y-282701D01*
X674851Y-282708D01*
X674826Y-282716D01*
X674793Y-282727D01*
X674756Y-282734D01*
X674717Y-282745D01*
X674669Y-282756D01*
X674615Y-282767D01*
X674556Y-282774D01*
X674494Y-282781D01*
X674425Y-282788D01*
X674353Y-282796D01*
X674272Y-282799D01*
X674189D01*
X674185D01*
X674167D01*
X674141D01*
X674109D01*
X674069Y-282796D01*
X674021D01*
X673967Y-282792D01*
X673912Y-282785D01*
X673788Y-282774D01*
X673657Y-282756D01*
X673533Y-282730D01*
X673472Y-282712D01*
X673417Y-282694D01*
X673413D01*
X673406Y-282690D01*
X673391Y-282683D01*
X673370Y-282676D01*
X673348Y-282665D01*
X673319Y-282650D01*
X673257Y-282614D01*
X673188Y-282570D01*
X673115Y-282519D01*
X673046Y-282454D01*
X672984Y-282381D01*
Y-282377D01*
X672977Y-282370D01*
X672969Y-282359D01*
X672962Y-282345D01*
X672951Y-282323D01*
X672936Y-282301D01*
X672922Y-282272D01*
X672911Y-282242D01*
X672882Y-282173D01*
X672857Y-282090D01*
X672842Y-281999D01*
X672835Y-281897D01*
Y-281868D01*
X672838Y-281849D01*
Y-281824D01*
X672842Y-281795D01*
X672857Y-281726D01*
X672875Y-281649D01*
X672904Y-281569D01*
X672944Y-281489D01*
X672969Y-281449D01*
X672998Y-281413D01*
X673002Y-281409D01*
X673006Y-281405D01*
X673017Y-281394D01*
X673028Y-281383D01*
X673046Y-281369D01*
X673068Y-281351D01*
X673118Y-281314D01*
X673184Y-281278D01*
X673264Y-281241D01*
X673355Y-281212D01*
X673461Y-281191D01*
X673486Y-281489D01*
X673483D01*
X673475Y-281493D01*
X673468D01*
X673453Y-281496D01*
X673413Y-281507D01*
X673370Y-281522D01*
X673319Y-281540D01*
X673268Y-281565D01*
X673220Y-281595D01*
X673180Y-281631D01*
X673177Y-281635D01*
X673166Y-281649D01*
X673151Y-281675D01*
X673137Y-281704D01*
X673118Y-281744D01*
X673104Y-281791D01*
X673093Y-281846D01*
X673089Y-281904D01*
Y-281929D01*
X673093Y-281955D01*
X673097Y-281988D01*
X673104Y-282028D01*
X673115Y-282068D01*
X673129Y-282112D01*
X673151Y-282152D01*
X673155Y-282155D01*
X673162Y-282170D01*
X673177Y-282192D01*
X673199Y-282213D01*
X673224Y-282242D01*
X673253Y-282272D01*
X673286Y-282301D01*
X673326Y-282330D01*
X673330Y-282333D01*
X673348Y-282341D01*
X673373Y-282355D01*
X673406Y-282370D01*
X673450Y-282388D01*
X673501Y-282406D01*
X673559Y-282424D01*
X673625Y-282443D01*
X673628D01*
X673632Y-282446D01*
X673643D01*
X673657Y-282450D01*
X673694Y-282457D01*
X673741Y-282468D01*
X673799Y-282475D01*
X673861Y-282483D01*
X673930Y-282486D01*
X674003Y-282490D01*
X674007D01*
X674018D01*
X674036D01*
X674065D01*
X674058Y-282486D01*
X674040Y-282472D01*
X674014Y-282450D01*
X673978Y-282424D01*
X673941Y-282388D01*
X673901Y-282345D01*
X673861Y-282294D01*
X673825Y-282235D01*
X673821Y-282228D01*
X673810Y-282206D01*
X673796Y-282173D01*
X673781Y-282133D01*
X673763Y-282079D01*
X673748Y-282020D01*
X673737Y-281955D01*
X673734Y-281886D01*
Y-281857D01*
X673737Y-281835D01*
X673741Y-281806D01*
X673745Y-281777D01*
X673752Y-281740D01*
X673763Y-281704D01*
X673788Y-281620D01*
X673806Y-281576D01*
X673828Y-281533D01*
X673854Y-281485D01*
X673887Y-281442D01*
X673919Y-281398D01*
X673959Y-281358D01*
X673963Y-281354D01*
X673970Y-281347D01*
X673981Y-281340D01*
X673999Y-281325D01*
X674025Y-281307D01*
X674050Y-281289D01*
X674083Y-281271D01*
X674120Y-281252D01*
X674160Y-281231D01*
X674203Y-281212D01*
X674254Y-281194D01*
X674305Y-281176D01*
X674363Y-281161D01*
X674425Y-281154D01*
X674487Y-281147D01*
X674556Y-281143D01*
X674560D01*
X674575D01*
X674593D01*
X674618Y-281147D01*
D02*
G37*
G36*
X32972Y15877D02*
X33019D01*
X33074Y15873D01*
X33128Y15866D01*
X33252Y15855D01*
X33383Y15837D01*
X33507Y15811D01*
X33569Y15793D01*
X33623Y15775D01*
X33627D01*
X33634Y15771D01*
X33649Y15764D01*
X33671Y15757D01*
X33692Y15746D01*
X33722Y15731D01*
X33783Y15695D01*
X33853Y15651D01*
X33925Y15600D01*
X33995Y15535D01*
X34056Y15462D01*
Y15458D01*
X34064Y15451D01*
X34071Y15440D01*
X34078Y15426D01*
X34089Y15404D01*
X34104Y15382D01*
X34118Y15353D01*
X34129Y15324D01*
X34158Y15255D01*
X34184Y15171D01*
X34198Y15080D01*
X34206Y14978D01*
Y14949D01*
X34202Y14931D01*
Y14905D01*
X34198Y14876D01*
X34184Y14807D01*
X34166Y14730D01*
X34137Y14650D01*
X34097Y14570D01*
X34071Y14530D01*
X34042Y14494D01*
X34038Y14490D01*
X34035Y14486D01*
X34024Y14476D01*
X34013Y14465D01*
X33995Y14450D01*
X33973Y14432D01*
X33922Y14395D01*
X33856Y14359D01*
X33776Y14323D01*
X33685Y14293D01*
X33580Y14272D01*
X33554Y14570D01*
X33558D01*
X33565Y14574D01*
X33572D01*
X33587Y14577D01*
X33627Y14588D01*
X33671Y14603D01*
X33722Y14621D01*
X33773Y14647D01*
X33820Y14676D01*
X33860Y14712D01*
X33863Y14716D01*
X33874Y14730D01*
X33889Y14756D01*
X33904Y14785D01*
X33922Y14825D01*
X33936Y14872D01*
X33947Y14927D01*
X33951Y14985D01*
Y15011D01*
X33947Y15036D01*
X33944Y15069D01*
X33936Y15109D01*
X33925Y15149D01*
X33911Y15193D01*
X33889Y15233D01*
X33885Y15236D01*
X33878Y15251D01*
X33863Y15273D01*
X33842Y15294D01*
X33816Y15324D01*
X33787Y15353D01*
X33754Y15382D01*
X33714Y15411D01*
X33711Y15415D01*
X33692Y15422D01*
X33667Y15437D01*
X33634Y15451D01*
X33590Y15469D01*
X33540Y15487D01*
X33481Y15506D01*
X33416Y15524D01*
X33412D01*
X33408Y15528D01*
X33398D01*
X33383Y15531D01*
X33347Y15538D01*
X33299Y15549D01*
X33241Y15557D01*
X33179Y15564D01*
X33110Y15567D01*
X33037Y15571D01*
X33034D01*
X33023D01*
X33005D01*
X32975D01*
X32983Y15567D01*
X33001Y15553D01*
X33026Y15531D01*
X33063Y15506D01*
X33099Y15469D01*
X33139Y15426D01*
X33179Y15375D01*
X33216Y15316D01*
X33219Y15309D01*
X33230Y15287D01*
X33245Y15255D01*
X33259Y15214D01*
X33277Y15160D01*
X33292Y15102D01*
X33303Y15036D01*
X33307Y14967D01*
Y14938D01*
X33303Y14916D01*
X33299Y14887D01*
X33296Y14858D01*
X33288Y14821D01*
X33277Y14785D01*
X33252Y14701D01*
X33234Y14658D01*
X33212Y14614D01*
X33187Y14567D01*
X33154Y14523D01*
X33121Y14479D01*
X33081Y14439D01*
X33077Y14435D01*
X33070Y14428D01*
X33059Y14421D01*
X33041Y14406D01*
X33015Y14388D01*
X32990Y14370D01*
X32957Y14352D01*
X32921Y14334D01*
X32881Y14312D01*
X32837Y14293D01*
X32786Y14275D01*
X32735Y14257D01*
X32677Y14243D01*
X32615Y14235D01*
X32553Y14228D01*
X32484Y14224D01*
X32480D01*
X32466D01*
X32448D01*
X32422Y14228D01*
X32389Y14232D01*
X32349Y14235D01*
X32309Y14243D01*
X32262Y14254D01*
X32167Y14279D01*
X32116Y14297D01*
X32062Y14319D01*
X32011Y14345D01*
X31963Y14377D01*
X31912Y14410D01*
X31869Y14450D01*
X31865Y14454D01*
X31858Y14461D01*
X31847Y14472D01*
X31832Y14490D01*
X31814Y14512D01*
X31792Y14541D01*
X31774Y14570D01*
X31749Y14607D01*
X31727Y14643D01*
X31709Y14687D01*
X31669Y14785D01*
X31654Y14836D01*
X31643Y14894D01*
X31636Y14952D01*
X31632Y15014D01*
Y15040D01*
X31636Y15058D01*
Y15076D01*
X31640Y15102D01*
X31650Y15164D01*
X31665Y15233D01*
X31690Y15309D01*
X31723Y15385D01*
X31767Y15462D01*
Y15466D01*
X31774Y15469D01*
X31781Y15480D01*
X31792Y15495D01*
X31822Y15531D01*
X31861Y15578D01*
X31916Y15626D01*
X31982Y15680D01*
X32058Y15728D01*
X32145Y15771D01*
X32149D01*
X32156Y15775D01*
X32171Y15782D01*
X32189Y15790D01*
X32215Y15797D01*
X32247Y15808D01*
X32284Y15815D01*
X32324Y15826D01*
X32371Y15837D01*
X32426Y15848D01*
X32484Y15855D01*
X32546Y15862D01*
X32615Y15870D01*
X32688Y15877D01*
X32768Y15881D01*
X32852D01*
X32855D01*
X32873D01*
X32899D01*
X32932D01*
X32972Y15877D01*
D02*
G37*
G36*
X32964Y13890D02*
X32994D01*
X33063Y13886D01*
X33143Y13875D01*
X33226Y13864D01*
X33314Y13846D01*
X33401Y13824D01*
X33405D01*
X33412Y13820D01*
X33423Y13817D01*
X33438Y13813D01*
X33478Y13799D01*
X33529Y13777D01*
X33587Y13755D01*
X33645Y13726D01*
X33707Y13689D01*
X33765Y13653D01*
X33773Y13649D01*
X33791Y13635D01*
X33816Y13613D01*
X33849Y13584D01*
X33885Y13551D01*
X33922Y13511D01*
X33962Y13471D01*
X33995Y13424D01*
X33998Y13416D01*
X34009Y13402D01*
X34024Y13376D01*
X34042Y13340D01*
X34064Y13296D01*
X34082Y13245D01*
X34104Y13187D01*
X34122Y13121D01*
Y13114D01*
X34126Y13103D01*
X34129Y13092D01*
X34133Y13056D01*
X34140Y13005D01*
X34147Y12947D01*
X34155Y12878D01*
X34158Y12801D01*
X34162Y12717D01*
Y11811D01*
X31643D01*
Y12779D01*
X31647Y12845D01*
X31650Y12918D01*
X31658Y12990D01*
X31669Y13063D01*
X31679Y13125D01*
Y13129D01*
X31683Y13136D01*
Y13147D01*
X31690Y13161D01*
X31701Y13202D01*
X31720Y13252D01*
X31745Y13311D01*
X31778Y13373D01*
X31814Y13434D01*
X31861Y13493D01*
X31865Y13496D01*
X31869Y13500D01*
X31880Y13511D01*
X31891Y13525D01*
X31927Y13562D01*
X31978Y13606D01*
X32040Y13653D01*
X32113Y13704D01*
X32196Y13751D01*
X32291Y13791D01*
X32295D01*
X32302Y13795D01*
X32316Y13802D01*
X32338Y13806D01*
X32364Y13817D01*
X32393Y13824D01*
X32426Y13831D01*
X32466Y13842D01*
X32506Y13853D01*
X32553Y13860D01*
X32655Y13879D01*
X32768Y13890D01*
X32892Y13893D01*
X32895D01*
X32903D01*
X32921D01*
X32939D01*
X32964Y13890D01*
D02*
G37*
G36*
X26584Y15873D02*
X26613Y15870D01*
X26646Y15862D01*
X26682Y15855D01*
X26723Y15848D01*
X26810Y15819D01*
X26857Y15797D01*
X26901Y15775D01*
X26948Y15746D01*
X26996Y15713D01*
X27043Y15677D01*
X27087Y15633D01*
X27090Y15629D01*
X27097Y15622D01*
X27108Y15608D01*
X27123Y15589D01*
X27141Y15567D01*
X27159Y15538D01*
X27181Y15506D01*
X27199Y15466D01*
X27221Y15426D01*
X27243Y15378D01*
X27261Y15331D01*
X27279Y15276D01*
X27294Y15218D01*
X27305Y15156D01*
X27312Y15094D01*
X27316Y15025D01*
Y14992D01*
X27312Y14971D01*
X27309Y14941D01*
X27305Y14909D01*
X27298Y14872D01*
X27290Y14832D01*
X27269Y14745D01*
X27232Y14654D01*
X27210Y14606D01*
X27185Y14563D01*
X27152Y14519D01*
X27119Y14476D01*
X27116Y14472D01*
X27108Y14465D01*
X27097Y14454D01*
X27083Y14443D01*
X27065Y14424D01*
X27039Y14406D01*
X27014Y14385D01*
X26981Y14363D01*
X26945Y14341D01*
X26908Y14319D01*
X26821Y14279D01*
X26719Y14246D01*
X26664Y14235D01*
X26606Y14228D01*
X26566Y14537D01*
X26570D01*
X26577Y14541D01*
X26592Y14545D01*
X26610Y14548D01*
X26632Y14552D01*
X26657Y14559D01*
X26712Y14577D01*
X26777Y14603D01*
X26839Y14636D01*
X26897Y14672D01*
X26948Y14716D01*
X26952Y14723D01*
X26967Y14738D01*
X26985Y14767D01*
X27003Y14803D01*
X27025Y14847D01*
X27043Y14901D01*
X27057Y14963D01*
X27061Y15029D01*
Y15051D01*
X27057Y15065D01*
X27054Y15105D01*
X27043Y15156D01*
X27025Y15214D01*
X26999Y15276D01*
X26963Y15338D01*
X26912Y15396D01*
X26905Y15404D01*
X26883Y15422D01*
X26850Y15444D01*
X26806Y15473D01*
X26752Y15502D01*
X26690Y15524D01*
X26617Y15542D01*
X26537Y15549D01*
X26533D01*
X26526D01*
X26515D01*
X26500Y15546D01*
X26460Y15542D01*
X26413Y15531D01*
X26355Y15517D01*
X26297Y15491D01*
X26239Y15455D01*
X26184Y15407D01*
X26177Y15400D01*
X26162Y15382D01*
X26140Y15353D01*
X26115Y15313D01*
X26089Y15262D01*
X26067Y15200D01*
X26053Y15131D01*
X26046Y15054D01*
Y15021D01*
X26049Y14996D01*
X26053Y14963D01*
X26060Y14927D01*
X26067Y14883D01*
X26078Y14836D01*
X25805Y14872D01*
Y14890D01*
X25809Y14905D01*
Y14952D01*
X25802Y14992D01*
X25794Y15040D01*
X25784Y15094D01*
X25765Y15156D01*
X25740Y15214D01*
X25707Y15276D01*
Y15280D01*
X25703Y15284D01*
X25689Y15302D01*
X25663Y15327D01*
X25631Y15356D01*
X25583Y15385D01*
X25529Y15411D01*
X25467Y15429D01*
X25430Y15437D01*
X25390D01*
X25387D01*
X25383D01*
X25361D01*
X25332Y15429D01*
X25292Y15422D01*
X25248Y15407D01*
X25201Y15389D01*
X25154Y15360D01*
X25110Y15320D01*
X25106Y15316D01*
X25092Y15298D01*
X25074Y15273D01*
X25052Y15240D01*
X25034Y15196D01*
X25015Y15145D01*
X25001Y15087D01*
X24997Y15021D01*
Y14992D01*
X25005Y14960D01*
X25012Y14916D01*
X25026Y14869D01*
X25045Y14821D01*
X25074Y14770D01*
X25110Y14723D01*
X25114Y14719D01*
X25132Y14705D01*
X25157Y14683D01*
X25194Y14658D01*
X25241Y14632D01*
X25299Y14606D01*
X25368Y14585D01*
X25449Y14570D01*
X25394Y14261D01*
X25390D01*
X25379Y14264D01*
X25365Y14268D01*
X25343Y14272D01*
X25317Y14279D01*
X25288Y14290D01*
X25219Y14312D01*
X25139Y14348D01*
X25059Y14392D01*
X24983Y14446D01*
X24914Y14515D01*
X24910Y14519D01*
X24906Y14526D01*
X24899Y14537D01*
X24888Y14552D01*
X24873Y14570D01*
X24859Y14596D01*
X24844Y14621D01*
X24826Y14654D01*
X24797Y14727D01*
X24768Y14810D01*
X24750Y14909D01*
X24742Y14960D01*
Y15051D01*
X24746Y15091D01*
X24753Y15138D01*
X24764Y15196D01*
X24782Y15262D01*
X24804Y15327D01*
X24833Y15393D01*
Y15396D01*
X24837Y15400D01*
X24848Y15422D01*
X24870Y15455D01*
X24895Y15491D01*
X24932Y15535D01*
X24972Y15578D01*
X25019Y15622D01*
X25074Y15658D01*
X25081Y15662D01*
X25099Y15673D01*
X25132Y15688D01*
X25172Y15706D01*
X25219Y15724D01*
X25274Y15739D01*
X25336Y15750D01*
X25398Y15753D01*
X25405D01*
X25427D01*
X25456Y15750D01*
X25496Y15742D01*
X25543Y15731D01*
X25594Y15713D01*
X25645Y15691D01*
X25696Y15662D01*
X25703Y15658D01*
X25718Y15648D01*
X25743Y15626D01*
X25773Y15597D01*
X25805Y15560D01*
X25842Y15517D01*
X25875Y15466D01*
X25907Y15404D01*
Y15407D01*
X25911Y15415D01*
X25914Y15426D01*
X25918Y15440D01*
X25933Y15480D01*
X25954Y15531D01*
X25984Y15589D01*
X26020Y15648D01*
X26067Y15702D01*
X26122Y15753D01*
X26129Y15757D01*
X26151Y15771D01*
X26188Y15793D01*
X26235Y15815D01*
X26293Y15837D01*
X26362Y15859D01*
X26442Y15873D01*
X26530Y15877D01*
X26533D01*
X26544D01*
X26562D01*
X26584Y15873D01*
D02*
G37*
G36*
X26075Y13890D02*
X26104D01*
X26173Y13886D01*
X26253Y13875D01*
X26337Y13864D01*
X26424Y13846D01*
X26511Y13824D01*
X26515D01*
X26522Y13820D01*
X26533Y13817D01*
X26548Y13813D01*
X26588Y13799D01*
X26639Y13777D01*
X26697Y13755D01*
X26755Y13726D01*
X26817Y13689D01*
X26875Y13653D01*
X26883Y13649D01*
X26901Y13635D01*
X26926Y13613D01*
X26959Y13584D01*
X26996Y13551D01*
X27032Y13511D01*
X27072Y13471D01*
X27105Y13424D01*
X27108Y13416D01*
X27119Y13402D01*
X27134Y13376D01*
X27152Y13340D01*
X27174Y13296D01*
X27192Y13245D01*
X27214Y13187D01*
X27232Y13121D01*
Y13114D01*
X27236Y13103D01*
X27240Y13092D01*
X27243Y13056D01*
X27250Y13005D01*
X27258Y12947D01*
X27265Y12878D01*
X27269Y12801D01*
X27272Y12717D01*
Y11811D01*
X24753D01*
Y12779D01*
X24757Y12845D01*
X24761Y12918D01*
X24768Y12990D01*
X24779Y13063D01*
X24790Y13125D01*
Y13129D01*
X24793Y13136D01*
Y13147D01*
X24801Y13161D01*
X24812Y13202D01*
X24830Y13252D01*
X24855Y13311D01*
X24888Y13373D01*
X24924Y13434D01*
X24972Y13493D01*
X24975Y13496D01*
X24979Y13500D01*
X24990Y13511D01*
X25001Y13525D01*
X25037Y13562D01*
X25088Y13605D01*
X25150Y13653D01*
X25223Y13704D01*
X25307Y13751D01*
X25401Y13791D01*
X25405D01*
X25412Y13795D01*
X25427Y13802D01*
X25449Y13806D01*
X25474Y13817D01*
X25503Y13824D01*
X25536Y13831D01*
X25576Y13842D01*
X25616Y13853D01*
X25663Y13860D01*
X25765Y13879D01*
X25878Y13890D01*
X26002Y13893D01*
X26006D01*
X26013D01*
X26031D01*
X26049D01*
X26075Y13890D01*
D02*
G37*
G36*
X642418Y-58911D02*
X642447Y-58914D01*
X642480Y-58918D01*
X642520Y-58922D01*
X642560Y-58933D01*
X642651Y-58954D01*
X642742Y-58987D01*
X642789Y-59009D01*
X642837Y-59034D01*
X642880Y-59064D01*
X642924Y-59096D01*
X642928Y-59100D01*
X642935Y-59104D01*
X642942Y-59118D01*
X642957Y-59133D01*
X642975Y-59151D01*
X642993Y-59173D01*
X643015Y-59202D01*
X643033Y-59235D01*
X643055Y-59267D01*
X643077Y-59307D01*
X643117Y-59395D01*
X643150Y-59497D01*
X643161Y-59551D01*
X643168Y-59610D01*
X642844Y-59635D01*
Y-59631D01*
Y-59624D01*
X642840Y-59613D01*
X642837Y-59595D01*
X642826Y-59555D01*
X642811Y-59500D01*
X642789Y-59446D01*
X642760Y-59384D01*
X642724Y-59329D01*
X642680Y-59278D01*
X642673Y-59275D01*
X642658Y-59260D01*
X642629Y-59242D01*
X642589Y-59220D01*
X642546Y-59198D01*
X642491Y-59180D01*
X642429Y-59166D01*
X642360Y-59162D01*
X642338D01*
X642323Y-59166D01*
X642280Y-59169D01*
X642229Y-59184D01*
X642167Y-59202D01*
X642105Y-59231D01*
X642039Y-59275D01*
X642010Y-59300D01*
X641981Y-59329D01*
X641978Y-59333D01*
X641974Y-59337D01*
X641967Y-59347D01*
X641956Y-59358D01*
X641930Y-59398D01*
X641901Y-59449D01*
X641876Y-59511D01*
X641850Y-59588D01*
X641832Y-59679D01*
X641825Y-59726D01*
Y-59777D01*
Y-59781D01*
Y-59788D01*
Y-59803D01*
X641828Y-59821D01*
Y-59842D01*
X641832Y-59868D01*
X641843Y-59926D01*
X641861Y-59995D01*
X641887Y-60065D01*
X641923Y-60130D01*
X641974Y-60192D01*
Y-60196D01*
X641981Y-60199D01*
X641999Y-60217D01*
X642032Y-60243D01*
X642076Y-60272D01*
X642134Y-60298D01*
X642200Y-60323D01*
X642276Y-60341D01*
X642320Y-60348D01*
X642389D01*
X642418Y-60345D01*
X642454Y-60341D01*
X642498Y-60330D01*
X642542Y-60319D01*
X642589Y-60301D01*
X642636Y-60279D01*
X642640Y-60276D01*
X642655Y-60268D01*
X642676Y-60250D01*
X642706Y-60232D01*
X642735Y-60207D01*
X642764Y-60174D01*
X642797Y-60141D01*
X642822Y-60101D01*
X643113Y-60141D01*
X642869Y-61437D01*
X641617D01*
Y-61142D01*
X642626D01*
X642760Y-60461D01*
X642757Y-60465D01*
X642749Y-60469D01*
X642738Y-60476D01*
X642720Y-60487D01*
X642698Y-60498D01*
X642673Y-60512D01*
X642615Y-60541D01*
X642542Y-60571D01*
X642462Y-60596D01*
X642374Y-60614D01*
X642331Y-60622D01*
X642251D01*
X642229Y-60618D01*
X642200Y-60614D01*
X642167Y-60611D01*
X642131Y-60603D01*
X642091Y-60592D01*
X642003Y-60567D01*
X641956Y-60549D01*
X641909Y-60523D01*
X641861Y-60498D01*
X641814Y-60469D01*
X641770Y-60432D01*
X641726Y-60392D01*
X641723Y-60388D01*
X641716Y-60381D01*
X641705Y-60370D01*
X641690Y-60352D01*
X641672Y-60327D01*
X641654Y-60301D01*
X641632Y-60268D01*
X641610Y-60232D01*
X641592Y-60192D01*
X641570Y-60148D01*
X641552Y-60097D01*
X641534Y-60046D01*
X641519Y-59992D01*
X641508Y-59930D01*
X641501Y-59868D01*
X641497Y-59803D01*
Y-59799D01*
Y-59788D01*
Y-59770D01*
X641501Y-59744D01*
X641504Y-59715D01*
X641508Y-59682D01*
X641515Y-59642D01*
X641523Y-59602D01*
X641544Y-59508D01*
X641581Y-59409D01*
X641603Y-59358D01*
X641632Y-59311D01*
X641661Y-59260D01*
X641697Y-59213D01*
X641701Y-59209D01*
X641708Y-59198D01*
X641723Y-59184D01*
X641741Y-59166D01*
X641767Y-59144D01*
X641796Y-59114D01*
X641832Y-59089D01*
X641872Y-59060D01*
X641916Y-59031D01*
X641967Y-59005D01*
X642021Y-58980D01*
X642080Y-58954D01*
X642141Y-58936D01*
X642211Y-58922D01*
X642283Y-58911D01*
X642360Y-58907D01*
X642393D01*
X642418Y-58911D01*
D02*
G37*
G36*
X644380D02*
X644409Y-58914D01*
X644442Y-58918D01*
X644478Y-58925D01*
X644518Y-58933D01*
X644606Y-58954D01*
X644697Y-58991D01*
X644744Y-59013D01*
X644788Y-59038D01*
X644831Y-59071D01*
X644875Y-59104D01*
X644879Y-59107D01*
X644886Y-59114D01*
X644897Y-59125D01*
X644908Y-59140D01*
X644926Y-59158D01*
X644944Y-59184D01*
X644966Y-59209D01*
X644988Y-59242D01*
X645010Y-59278D01*
X645032Y-59315D01*
X645072Y-59402D01*
X645104Y-59504D01*
X645115Y-59559D01*
X645123Y-59617D01*
X644813Y-59657D01*
Y-59653D01*
X644810Y-59646D01*
X644806Y-59631D01*
X644802Y-59613D01*
X644799Y-59591D01*
X644791Y-59566D01*
X644773Y-59511D01*
X644748Y-59446D01*
X644715Y-59384D01*
X644678Y-59326D01*
X644635Y-59275D01*
X644628Y-59271D01*
X644613Y-59257D01*
X644584Y-59238D01*
X644548Y-59220D01*
X644504Y-59198D01*
X644449Y-59180D01*
X644387Y-59166D01*
X644322Y-59162D01*
X644300D01*
X644285Y-59166D01*
X644245Y-59169D01*
X644194Y-59180D01*
X644136Y-59198D01*
X644074Y-59224D01*
X644012Y-59260D01*
X643954Y-59311D01*
X643947Y-59318D01*
X643929Y-59340D01*
X643907Y-59373D01*
X643878Y-59417D01*
X643849Y-59471D01*
X643827Y-59533D01*
X643809Y-59606D01*
X643801Y-59686D01*
Y-59690D01*
Y-59697D01*
Y-59708D01*
X643805Y-59722D01*
X643809Y-59762D01*
X643820Y-59810D01*
X643834Y-59868D01*
X643859Y-59926D01*
X643896Y-59984D01*
X643943Y-60039D01*
X643951Y-60046D01*
X643969Y-60061D01*
X643998Y-60083D01*
X644038Y-60108D01*
X644089Y-60134D01*
X644151Y-60156D01*
X644220Y-60170D01*
X644296Y-60177D01*
X644329D01*
X644355Y-60174D01*
X644387Y-60170D01*
X644424Y-60163D01*
X644467Y-60156D01*
X644515Y-60145D01*
X644478Y-60418D01*
X644460D01*
X644446Y-60414D01*
X644398D01*
X644358Y-60421D01*
X644311Y-60429D01*
X644256Y-60439D01*
X644194Y-60458D01*
X644136Y-60483D01*
X644074Y-60516D01*
X644071D01*
X644067Y-60520D01*
X644049Y-60534D01*
X644023Y-60560D01*
X643994Y-60592D01*
X643965Y-60640D01*
X643940Y-60694D01*
X643921Y-60756D01*
X643914Y-60793D01*
Y-60833D01*
Y-60836D01*
Y-60840D01*
Y-60862D01*
X643921Y-60891D01*
X643929Y-60931D01*
X643943Y-60975D01*
X643961Y-61022D01*
X643991Y-61069D01*
X644031Y-61113D01*
X644034Y-61116D01*
X644053Y-61131D01*
X644078Y-61149D01*
X644111Y-61171D01*
X644154Y-61189D01*
X644205Y-61207D01*
X644264Y-61222D01*
X644329Y-61226D01*
X644358D01*
X644391Y-61218D01*
X644435Y-61211D01*
X644482Y-61197D01*
X644529Y-61178D01*
X644580Y-61149D01*
X644628Y-61113D01*
X644631Y-61109D01*
X644646Y-61091D01*
X644668Y-61066D01*
X644693Y-61029D01*
X644719Y-60982D01*
X644744Y-60924D01*
X644766Y-60854D01*
X644780Y-60774D01*
X645090Y-60829D01*
Y-60833D01*
X645086Y-60843D01*
X645083Y-60858D01*
X645079Y-60880D01*
X645072Y-60905D01*
X645061Y-60935D01*
X645039Y-61004D01*
X645003Y-61084D01*
X644959Y-61164D01*
X644904Y-61240D01*
X644835Y-61309D01*
X644831Y-61313D01*
X644824Y-61317D01*
X644813Y-61324D01*
X644799Y-61335D01*
X644780Y-61349D01*
X644755Y-61364D01*
X644730Y-61379D01*
X644697Y-61397D01*
X644624Y-61426D01*
X644540Y-61455D01*
X644442Y-61473D01*
X644391Y-61480D01*
X644300D01*
X644260Y-61477D01*
X644213Y-61470D01*
X644154Y-61459D01*
X644089Y-61440D01*
X644023Y-61419D01*
X643958Y-61389D01*
X643954D01*
X643951Y-61386D01*
X643929Y-61375D01*
X643896Y-61353D01*
X643859Y-61328D01*
X643816Y-61291D01*
X643772Y-61251D01*
X643728Y-61204D01*
X643692Y-61149D01*
X643688Y-61142D01*
X643678Y-61124D01*
X643663Y-61091D01*
X643645Y-61051D01*
X643627Y-61004D01*
X643612Y-60949D01*
X643601Y-60887D01*
X643598Y-60825D01*
Y-60818D01*
Y-60796D01*
X643601Y-60767D01*
X643608Y-60727D01*
X643619Y-60680D01*
X643638Y-60629D01*
X643659Y-60578D01*
X643688Y-60527D01*
X643692Y-60520D01*
X643703Y-60505D01*
X643725Y-60479D01*
X643754Y-60450D01*
X643790Y-60418D01*
X643834Y-60381D01*
X643885Y-60348D01*
X643947Y-60316D01*
X643943D01*
X643936Y-60312D01*
X643925Y-60308D01*
X643911Y-60305D01*
X643870Y-60290D01*
X643820Y-60268D01*
X643761Y-60239D01*
X643703Y-60203D01*
X643648Y-60156D01*
X643598Y-60101D01*
X643594Y-60094D01*
X643579Y-60072D01*
X643557Y-60035D01*
X643536Y-59988D01*
X643514Y-59930D01*
X643492Y-59861D01*
X643477Y-59781D01*
X643474Y-59693D01*
Y-59690D01*
Y-59679D01*
Y-59661D01*
X643477Y-59639D01*
X643481Y-59610D01*
X643488Y-59577D01*
X643496Y-59540D01*
X643503Y-59500D01*
X643532Y-59413D01*
X643554Y-59366D01*
X643576Y-59322D01*
X643605Y-59275D01*
X643638Y-59227D01*
X643674Y-59180D01*
X643718Y-59136D01*
X643721Y-59133D01*
X643728Y-59125D01*
X643743Y-59114D01*
X643761Y-59100D01*
X643783Y-59082D01*
X643812Y-59064D01*
X643845Y-59042D01*
X643885Y-59023D01*
X643925Y-59002D01*
X643972Y-58980D01*
X644020Y-58962D01*
X644074Y-58943D01*
X644133Y-58929D01*
X644194Y-58918D01*
X644256Y-58911D01*
X644325Y-58907D01*
X644358D01*
X644380Y-58911D01*
D02*
G37*
G36*
X646524D02*
X646557D01*
X646597Y-58914D01*
X646640Y-58922D01*
X646691Y-58929D01*
X646797Y-58947D01*
X646906Y-58976D01*
X647015Y-59016D01*
X647066Y-59042D01*
X647117Y-59071D01*
X647121Y-59074D01*
X647128Y-59078D01*
X647143Y-59089D01*
X647157Y-59104D01*
X647179Y-59118D01*
X647205Y-59140D01*
X647234Y-59166D01*
X647263Y-59195D01*
X647292Y-59227D01*
X647325Y-59260D01*
X647390Y-59344D01*
X647452Y-59442D01*
X647507Y-59551D01*
Y-59555D01*
X647514Y-59566D01*
X647518Y-59584D01*
X647529Y-59606D01*
X647536Y-59635D01*
X647547Y-59671D01*
X647561Y-59711D01*
X647572Y-59755D01*
X647583Y-59803D01*
X647598Y-59857D01*
X647616Y-59970D01*
X647631Y-60097D01*
X647638Y-60228D01*
Y-60232D01*
Y-60247D01*
Y-60268D01*
X647634Y-60294D01*
Y-60330D01*
X647631Y-60367D01*
X647627Y-60414D01*
X647620Y-60461D01*
X647602Y-60567D01*
X647576Y-60683D01*
X647540Y-60800D01*
X647489Y-60913D01*
X647485Y-60916D01*
X647481Y-60927D01*
X647474Y-60942D01*
X647460Y-60960D01*
X647445Y-60985D01*
X647427Y-61015D01*
X647379Y-61080D01*
X647318Y-61153D01*
X647245Y-61226D01*
X647161Y-61299D01*
X647063Y-61360D01*
X647059Y-61364D01*
X647048Y-61368D01*
X647034Y-61375D01*
X647015Y-61386D01*
X646986Y-61397D01*
X646957Y-61408D01*
X646921Y-61422D01*
X646881Y-61437D01*
X646837Y-61451D01*
X646790Y-61466D01*
X646688Y-61488D01*
X646571Y-61506D01*
X646451Y-61513D01*
X646415D01*
X646389Y-61510D01*
X646357Y-61506D01*
X646316Y-61502D01*
X646277Y-61499D01*
X646229Y-61488D01*
X646131Y-61466D01*
X646022Y-61433D01*
X645967Y-61411D01*
X645916Y-61386D01*
X645865Y-61353D01*
X645814Y-61320D01*
X645811Y-61317D01*
X645803Y-61313D01*
X645789Y-61302D01*
X645771Y-61284D01*
X645752Y-61266D01*
X645727Y-61240D01*
X645701Y-61211D01*
X645672Y-61182D01*
X645643Y-61146D01*
X645614Y-61102D01*
X645581Y-61058D01*
X645552Y-61011D01*
X645527Y-60956D01*
X645498Y-60902D01*
X645476Y-60843D01*
X645454Y-60778D01*
X645782Y-60702D01*
Y-60705D01*
X645785Y-60712D01*
X645792Y-60727D01*
X645800Y-60745D01*
X645807Y-60767D01*
X645818Y-60796D01*
X645847Y-60854D01*
X645883Y-60920D01*
X645927Y-60985D01*
X645982Y-61047D01*
X646040Y-61102D01*
X646047Y-61109D01*
X646069Y-61124D01*
X646105Y-61142D01*
X646153Y-61168D01*
X646215Y-61189D01*
X646284Y-61211D01*
X646368Y-61226D01*
X646458Y-61229D01*
X646488D01*
X646506Y-61226D01*
X646531D01*
X646560Y-61222D01*
X646630Y-61211D01*
X646706Y-61197D01*
X646786Y-61171D01*
X646870Y-61135D01*
X646946Y-61087D01*
X646950D01*
X646953Y-61080D01*
X646979Y-61062D01*
X647012Y-61033D01*
X647052Y-60989D01*
X647099Y-60935D01*
X647143Y-60873D01*
X647183Y-60796D01*
X647219Y-60712D01*
Y-60709D01*
X647223Y-60702D01*
X647226Y-60691D01*
X647230Y-60672D01*
X647237Y-60651D01*
X647245Y-60625D01*
X647256Y-60563D01*
X647270Y-60490D01*
X647285Y-60410D01*
X647292Y-60323D01*
X647296Y-60228D01*
Y-60225D01*
Y-60214D01*
Y-60196D01*
Y-60174D01*
X647292Y-60148D01*
Y-60115D01*
X647288Y-60079D01*
X647285Y-60039D01*
X647274Y-59952D01*
X647256Y-59857D01*
X647234Y-59762D01*
X647205Y-59668D01*
Y-59664D01*
X647201Y-59657D01*
X647194Y-59646D01*
X647187Y-59628D01*
X647165Y-59584D01*
X647132Y-59533D01*
X647092Y-59475D01*
X647041Y-59413D01*
X646983Y-59358D01*
X646913Y-59307D01*
X646910D01*
X646903Y-59304D01*
X646892Y-59297D01*
X646877Y-59289D01*
X646859Y-59282D01*
X646837Y-59271D01*
X646786Y-59249D01*
X646721Y-59227D01*
X646648Y-59209D01*
X646568Y-59195D01*
X646484Y-59191D01*
X646458D01*
X646437Y-59195D01*
X646411D01*
X646386Y-59198D01*
X646320Y-59213D01*
X646244Y-59231D01*
X646167Y-59260D01*
X646087Y-59300D01*
X646047Y-59322D01*
X646011Y-59351D01*
X646007Y-59355D01*
X646003Y-59358D01*
X645993Y-59369D01*
X645978Y-59380D01*
X645963Y-59398D01*
X645945Y-59420D01*
X645923Y-59442D01*
X645905Y-59471D01*
X645883Y-59504D01*
X645858Y-59540D01*
X645836Y-59577D01*
X645814Y-59620D01*
X645796Y-59668D01*
X645778Y-59719D01*
X645760Y-59773D01*
X645745Y-59832D01*
X645410Y-59748D01*
Y-59744D01*
X645414Y-59730D01*
X645421Y-59708D01*
X645432Y-59679D01*
X645443Y-59646D01*
X645458Y-59606D01*
X645476Y-59562D01*
X645498Y-59515D01*
X645548Y-59413D01*
X645614Y-59311D01*
X645654Y-59260D01*
X645694Y-59209D01*
X645738Y-59166D01*
X645789Y-59122D01*
X645792Y-59118D01*
X645800Y-59111D01*
X645818Y-59104D01*
X645836Y-59089D01*
X645865Y-59071D01*
X645894Y-59053D01*
X645934Y-59034D01*
X645974Y-59016D01*
X646022Y-58994D01*
X646073Y-58976D01*
X646127Y-58958D01*
X646185Y-58940D01*
X646247Y-58925D01*
X646313Y-58918D01*
X646382Y-58911D01*
X646455Y-58907D01*
X646495D01*
X646524Y-58911D01*
D02*
G37*
G36*
X609931Y-21509D02*
X609960Y-21513D01*
X609993Y-21516D01*
X610030Y-21524D01*
X610070Y-21531D01*
X610157Y-21553D01*
X610248Y-21589D01*
X610295Y-21611D01*
X610339Y-21636D01*
X610383Y-21669D01*
X610426Y-21702D01*
X610430Y-21706D01*
X610437Y-21713D01*
X610448Y-21724D01*
X610459Y-21738D01*
X610477Y-21757D01*
X610495Y-21782D01*
X610517Y-21808D01*
X610539Y-21840D01*
X610561Y-21877D01*
X610583Y-21913D01*
X610623Y-22001D01*
X610656Y-22102D01*
X610667Y-22157D01*
X610674Y-22215D01*
X610364Y-22255D01*
Y-22252D01*
X610361Y-22244D01*
X610357Y-22230D01*
X610354Y-22212D01*
X610350Y-22190D01*
X610343Y-22164D01*
X610324Y-22110D01*
X610299Y-22044D01*
X610266Y-21982D01*
X610230Y-21924D01*
X610186Y-21873D01*
X610179Y-21869D01*
X610164Y-21855D01*
X610135Y-21837D01*
X610099Y-21818D01*
X610055Y-21797D01*
X610000Y-21779D01*
X609938Y-21764D01*
X609873Y-21760D01*
X609851D01*
X609837Y-21764D01*
X609797Y-21768D01*
X609746Y-21779D01*
X609687Y-21797D01*
X609625Y-21822D01*
X609564Y-21858D01*
X609505Y-21910D01*
X609498Y-21917D01*
X609480Y-21939D01*
X609458Y-21971D01*
X609429Y-22015D01*
X609400Y-22070D01*
X609378Y-22131D01*
X609360Y-22204D01*
X609352Y-22284D01*
Y-22288D01*
Y-22295D01*
Y-22306D01*
X609356Y-22321D01*
X609360Y-22361D01*
X609371Y-22408D01*
X609385Y-22466D01*
X609411Y-22525D01*
X609447Y-22583D01*
X609494Y-22637D01*
X609502Y-22645D01*
X609520Y-22659D01*
X609549Y-22681D01*
X609589Y-22707D01*
X609640Y-22732D01*
X609702Y-22754D01*
X609771Y-22769D01*
X609847Y-22776D01*
X609880D01*
X609906Y-22772D01*
X609938Y-22769D01*
X609975Y-22761D01*
X610019Y-22754D01*
X610066Y-22743D01*
X610030Y-23016D01*
X610011D01*
X609997Y-23012D01*
X609949D01*
X609909Y-23020D01*
X609862Y-23027D01*
X609807Y-23038D01*
X609746Y-23056D01*
X609687Y-23082D01*
X609625Y-23114D01*
X609622D01*
X609618Y-23118D01*
X609600Y-23133D01*
X609575Y-23158D01*
X609545Y-23191D01*
X609516Y-23238D01*
X609491Y-23293D01*
X609473Y-23355D01*
X609465Y-23391D01*
Y-23431D01*
Y-23435D01*
Y-23438D01*
Y-23460D01*
X609473Y-23489D01*
X609480Y-23529D01*
X609494Y-23573D01*
X609513Y-23620D01*
X609542Y-23668D01*
X609582Y-23711D01*
X609585Y-23715D01*
X609604Y-23730D01*
X609629Y-23748D01*
X609662Y-23769D01*
X609706Y-23788D01*
X609757Y-23806D01*
X609815Y-23821D01*
X609880Y-23824D01*
X609909D01*
X609942Y-23817D01*
X609986Y-23810D01*
X610033Y-23795D01*
X610080Y-23777D01*
X610131Y-23748D01*
X610179Y-23711D01*
X610182Y-23708D01*
X610197Y-23689D01*
X610219Y-23664D01*
X610244Y-23628D01*
X610270Y-23580D01*
X610295Y-23522D01*
X610317Y-23453D01*
X610332Y-23373D01*
X610641Y-23427D01*
Y-23431D01*
X610637Y-23442D01*
X610634Y-23457D01*
X610630Y-23478D01*
X610623Y-23504D01*
X610612Y-23533D01*
X610590Y-23602D01*
X610554Y-23682D01*
X610510Y-23762D01*
X610455Y-23839D01*
X610386Y-23908D01*
X610383Y-23911D01*
X610375Y-23915D01*
X610364Y-23922D01*
X610350Y-23933D01*
X610332Y-23948D01*
X610306Y-23963D01*
X610281Y-23977D01*
X610248Y-23995D01*
X610175Y-24024D01*
X610091Y-24054D01*
X609993Y-24072D01*
X609942Y-24079D01*
X609851D01*
X609811Y-24075D01*
X609764Y-24068D01*
X609706Y-24057D01*
X609640Y-24039D01*
X609575Y-24017D01*
X609509Y-23988D01*
X609505D01*
X609502Y-23984D01*
X609480Y-23973D01*
X609447Y-23952D01*
X609411Y-23926D01*
X609367Y-23890D01*
X609323Y-23850D01*
X609280Y-23802D01*
X609243Y-23748D01*
X609240Y-23740D01*
X609229Y-23722D01*
X609214Y-23689D01*
X609196Y-23649D01*
X609178Y-23602D01*
X609163Y-23548D01*
X609152Y-23486D01*
X609149Y-23424D01*
Y-23416D01*
Y-23395D01*
X609152Y-23366D01*
X609160Y-23325D01*
X609170Y-23278D01*
X609189Y-23227D01*
X609210Y-23176D01*
X609240Y-23125D01*
X609243Y-23118D01*
X609254Y-23103D01*
X609276Y-23078D01*
X609305Y-23049D01*
X609342Y-23016D01*
X609385Y-22980D01*
X609436Y-22947D01*
X609498Y-22914D01*
X609494D01*
X609487Y-22910D01*
X609476Y-22907D01*
X609462Y-22903D01*
X609422Y-22889D01*
X609371Y-22867D01*
X609312Y-22838D01*
X609254Y-22801D01*
X609200Y-22754D01*
X609149Y-22699D01*
X609145Y-22692D01*
X609130Y-22670D01*
X609109Y-22634D01*
X609087Y-22587D01*
X609065Y-22528D01*
X609043Y-22459D01*
X609028Y-22379D01*
X609025Y-22292D01*
Y-22288D01*
Y-22277D01*
Y-22259D01*
X609028Y-22237D01*
X609032Y-22208D01*
X609039Y-22175D01*
X609047Y-22139D01*
X609054Y-22099D01*
X609083Y-22011D01*
X609105Y-21964D01*
X609127Y-21920D01*
X609156Y-21873D01*
X609189Y-21826D01*
X609225Y-21779D01*
X609269Y-21735D01*
X609272Y-21731D01*
X609280Y-21724D01*
X609294Y-21713D01*
X609312Y-21698D01*
X609334Y-21680D01*
X609363Y-21662D01*
X609396Y-21640D01*
X609436Y-21622D01*
X609476Y-21600D01*
X609523Y-21578D01*
X609571Y-21560D01*
X609625Y-21542D01*
X609684Y-21527D01*
X609746Y-21516D01*
X609807Y-21509D01*
X609877Y-21506D01*
X609909D01*
X609931Y-21509D01*
D02*
G37*
G36*
X612075D02*
X612108D01*
X612148Y-21513D01*
X612192Y-21520D01*
X612243Y-21527D01*
X612348Y-21545D01*
X612457Y-21575D01*
X612567Y-21615D01*
X612618Y-21640D01*
X612669Y-21669D01*
X612672Y-21673D01*
X612679Y-21677D01*
X612694Y-21688D01*
X612709Y-21702D01*
X612730Y-21717D01*
X612756Y-21738D01*
X612785Y-21764D01*
X612814Y-21793D01*
X612843Y-21826D01*
X612876Y-21858D01*
X612942Y-21942D01*
X613003Y-22040D01*
X613058Y-22150D01*
Y-22153D01*
X613065Y-22164D01*
X613069Y-22183D01*
X613080Y-22204D01*
X613087Y-22233D01*
X613098Y-22270D01*
X613113Y-22310D01*
X613124Y-22354D01*
X613134Y-22401D01*
X613149Y-22456D01*
X613167Y-22568D01*
X613182Y-22696D01*
X613189Y-22827D01*
Y-22830D01*
Y-22845D01*
Y-22867D01*
X613185Y-22892D01*
Y-22929D01*
X613182Y-22965D01*
X613178Y-23012D01*
X613171Y-23060D01*
X613153Y-23165D01*
X613127Y-23282D01*
X613091Y-23398D01*
X613040Y-23511D01*
X613036Y-23515D01*
X613032Y-23526D01*
X613025Y-23540D01*
X613011Y-23558D01*
X612996Y-23584D01*
X612978Y-23613D01*
X612931Y-23678D01*
X612869Y-23751D01*
X612796Y-23824D01*
X612712Y-23897D01*
X612614Y-23959D01*
X612610Y-23963D01*
X612599Y-23966D01*
X612585Y-23973D01*
X612567Y-23984D01*
X612537Y-23995D01*
X612508Y-24006D01*
X612472Y-24021D01*
X612432Y-24035D01*
X612388Y-24050D01*
X612341Y-24064D01*
X612239Y-24086D01*
X612122Y-24104D01*
X612002Y-24112D01*
X611966D01*
X611940Y-24108D01*
X611908Y-24104D01*
X611868Y-24101D01*
X611828Y-24097D01*
X611780Y-24086D01*
X611682Y-24064D01*
X611573Y-24032D01*
X611518Y-24010D01*
X611467Y-23984D01*
X611416Y-23952D01*
X611365Y-23919D01*
X611362Y-23915D01*
X611354Y-23911D01*
X611340Y-23901D01*
X611322Y-23882D01*
X611304Y-23864D01*
X611278Y-23839D01*
X611252Y-23810D01*
X611223Y-23780D01*
X611194Y-23744D01*
X611165Y-23700D01*
X611132Y-23657D01*
X611103Y-23609D01*
X611078Y-23555D01*
X611049Y-23500D01*
X611027Y-23442D01*
X611005Y-23376D01*
X611333Y-23300D01*
Y-23304D01*
X611336Y-23311D01*
X611343Y-23325D01*
X611351Y-23344D01*
X611358Y-23366D01*
X611369Y-23395D01*
X611398Y-23453D01*
X611435Y-23518D01*
X611478Y-23584D01*
X611533Y-23646D01*
X611591Y-23700D01*
X611598Y-23708D01*
X611620Y-23722D01*
X611657Y-23740D01*
X611704Y-23766D01*
X611766Y-23788D01*
X611835Y-23810D01*
X611919Y-23824D01*
X612010Y-23828D01*
X612039D01*
X612057Y-23824D01*
X612082D01*
X612112Y-23821D01*
X612181Y-23810D01*
X612257Y-23795D01*
X612337Y-23769D01*
X612421Y-23733D01*
X612497Y-23686D01*
X612501D01*
X612505Y-23678D01*
X612530Y-23660D01*
X612563Y-23631D01*
X612603Y-23587D01*
X612650Y-23533D01*
X612694Y-23471D01*
X612734Y-23395D01*
X612770Y-23311D01*
Y-23307D01*
X612774Y-23300D01*
X612778Y-23289D01*
X612781Y-23271D01*
X612789Y-23249D01*
X612796Y-23223D01*
X612807Y-23162D01*
X612821Y-23089D01*
X612836Y-23009D01*
X612843Y-22921D01*
X612847Y-22827D01*
Y-22823D01*
Y-22812D01*
Y-22794D01*
Y-22772D01*
X612843Y-22747D01*
Y-22714D01*
X612840Y-22678D01*
X612836Y-22637D01*
X612825Y-22550D01*
X612807Y-22456D01*
X612785Y-22361D01*
X612756Y-22266D01*
Y-22263D01*
X612752Y-22255D01*
X612745Y-22244D01*
X612738Y-22226D01*
X612716Y-22183D01*
X612683Y-22131D01*
X612643Y-22073D01*
X612592Y-22011D01*
X612534Y-21957D01*
X612465Y-21906D01*
X612461D01*
X612454Y-21902D01*
X612443Y-21895D01*
X612428Y-21888D01*
X612410Y-21880D01*
X612388Y-21869D01*
X612337Y-21848D01*
X612272Y-21826D01*
X612199Y-21808D01*
X612119Y-21793D01*
X612035Y-21789D01*
X612010D01*
X611988Y-21793D01*
X611962D01*
X611937Y-21797D01*
X611871Y-21811D01*
X611795Y-21829D01*
X611719Y-21858D01*
X611638Y-21899D01*
X611598Y-21920D01*
X611562Y-21949D01*
X611558Y-21953D01*
X611555Y-21957D01*
X611544Y-21968D01*
X611529Y-21979D01*
X611515Y-21997D01*
X611496Y-22019D01*
X611475Y-22040D01*
X611456Y-22070D01*
X611435Y-22102D01*
X611409Y-22139D01*
X611387Y-22175D01*
X611365Y-22219D01*
X611347Y-22266D01*
X611329Y-22317D01*
X611311Y-22372D01*
X611296Y-22430D01*
X610961Y-22346D01*
Y-22343D01*
X610965Y-22328D01*
X610972Y-22306D01*
X610983Y-22277D01*
X610994Y-22244D01*
X611009Y-22204D01*
X611027Y-22161D01*
X611049Y-22113D01*
X611100Y-22011D01*
X611165Y-21910D01*
X611205Y-21858D01*
X611245Y-21808D01*
X611289Y-21764D01*
X611340Y-21720D01*
X611343Y-21717D01*
X611351Y-21709D01*
X611369Y-21702D01*
X611387Y-21688D01*
X611416Y-21669D01*
X611446Y-21651D01*
X611485Y-21633D01*
X611526Y-21615D01*
X611573Y-21593D01*
X611624Y-21575D01*
X611678Y-21556D01*
X611737Y-21538D01*
X611798Y-21524D01*
X611864Y-21516D01*
X611933Y-21509D01*
X612006Y-21506D01*
X612046D01*
X612075Y-21509D01*
D02*
G37*
G36*
X607729Y-22153D02*
X608825D01*
Y-22437D01*
X607671Y-24068D01*
X607420D01*
Y-22437D01*
X607078D01*
Y-22153D01*
X607420D01*
Y-21549D01*
X607729D01*
Y-22153D01*
D02*
G37*
G36*
X90954Y-94344D02*
X90990D01*
X91027Y-94347D01*
X91074Y-94351D01*
X91121Y-94358D01*
X91227Y-94376D01*
X91343Y-94402D01*
X91460Y-94438D01*
X91573Y-94489D01*
X91576Y-94493D01*
X91587Y-94497D01*
X91602Y-94504D01*
X91620Y-94519D01*
X91645Y-94533D01*
X91675Y-94551D01*
X91740Y-94599D01*
X91813Y-94661D01*
X91886Y-94733D01*
X91958Y-94817D01*
X92020Y-94915D01*
X92024Y-94919D01*
X92027Y-94930D01*
X92035Y-94944D01*
X92046Y-94963D01*
X92057Y-94992D01*
X92068Y-95021D01*
X92082Y-95057D01*
X92097Y-95097D01*
X92111Y-95141D01*
X92126Y-95188D01*
X92148Y-95290D01*
X92166Y-95407D01*
X92173Y-95527D01*
Y-95563D01*
X92169Y-95589D01*
X92166Y-95621D01*
X92162Y-95661D01*
X92159Y-95701D01*
X92148Y-95749D01*
X92126Y-95847D01*
X92093Y-95956D01*
X92071Y-96011D01*
X92046Y-96062D01*
X92013Y-96113D01*
X91980Y-96164D01*
X91977Y-96167D01*
X91973Y-96175D01*
X91962Y-96189D01*
X91944Y-96207D01*
X91926Y-96226D01*
X91900Y-96251D01*
X91871Y-96277D01*
X91842Y-96306D01*
X91805Y-96335D01*
X91762Y-96364D01*
X91718Y-96397D01*
X91671Y-96426D01*
X91616Y-96451D01*
X91562Y-96480D01*
X91503Y-96502D01*
X91438Y-96524D01*
X91361Y-96197D01*
X91365D01*
X91372Y-96193D01*
X91387Y-96186D01*
X91405Y-96178D01*
X91427Y-96171D01*
X91456Y-96160D01*
X91514Y-96131D01*
X91580Y-96095D01*
X91645Y-96051D01*
X91707Y-95996D01*
X91762Y-95938D01*
X91769Y-95931D01*
X91784Y-95909D01*
X91802Y-95873D01*
X91827Y-95825D01*
X91849Y-95763D01*
X91871Y-95694D01*
X91886Y-95610D01*
X91889Y-95520D01*
Y-95490D01*
X91886Y-95472D01*
Y-95447D01*
X91882Y-95418D01*
X91871Y-95348D01*
X91856Y-95272D01*
X91831Y-95192D01*
X91795Y-95108D01*
X91747Y-95032D01*
Y-95028D01*
X91740Y-95025D01*
X91722Y-94999D01*
X91693Y-94966D01*
X91649Y-94926D01*
X91594Y-94879D01*
X91532Y-94835D01*
X91456Y-94795D01*
X91372Y-94759D01*
X91369D01*
X91361Y-94755D01*
X91351Y-94751D01*
X91332Y-94748D01*
X91311Y-94740D01*
X91285Y-94733D01*
X91223Y-94722D01*
X91150Y-94708D01*
X91070Y-94693D01*
X90983Y-94686D01*
X90888Y-94682D01*
X90885D01*
X90874D01*
X90855D01*
X90834D01*
X90808Y-94686D01*
X90775D01*
X90739Y-94690D01*
X90699Y-94693D01*
X90612Y-94704D01*
X90517Y-94722D01*
X90422Y-94744D01*
X90328Y-94773D01*
X90324D01*
X90317Y-94777D01*
X90306Y-94784D01*
X90288Y-94792D01*
X90244Y-94813D01*
X90193Y-94846D01*
X90135Y-94886D01*
X90073Y-94937D01*
X90018Y-94995D01*
X89967Y-95065D01*
Y-95068D01*
X89964Y-95075D01*
X89956Y-95086D01*
X89949Y-95101D01*
X89942Y-95119D01*
X89931Y-95141D01*
X89909Y-95192D01*
X89887Y-95257D01*
X89869Y-95330D01*
X89855Y-95410D01*
X89851Y-95494D01*
Y-95520D01*
X89855Y-95541D01*
Y-95567D01*
X89858Y-95592D01*
X89873Y-95658D01*
X89891Y-95734D01*
X89920Y-95811D01*
X89960Y-95891D01*
X89982Y-95931D01*
X90011Y-95967D01*
X90015Y-95971D01*
X90018Y-95974D01*
X90029Y-95985D01*
X90040Y-96000D01*
X90058Y-96014D01*
X90080Y-96033D01*
X90102Y-96055D01*
X90131Y-96073D01*
X90164Y-96095D01*
X90200Y-96120D01*
X90237Y-96142D01*
X90280Y-96164D01*
X90328Y-96182D01*
X90379Y-96200D01*
X90433Y-96218D01*
X90491Y-96233D01*
X90408Y-96568D01*
X90404D01*
X90390Y-96564D01*
X90368Y-96557D01*
X90339Y-96546D01*
X90306Y-96535D01*
X90266Y-96521D01*
X90222Y-96502D01*
X90175Y-96480D01*
X90073Y-96430D01*
X89971Y-96364D01*
X89920Y-96324D01*
X89869Y-96284D01*
X89825Y-96240D01*
X89782Y-96189D01*
X89778Y-96186D01*
X89771Y-96178D01*
X89763Y-96160D01*
X89749Y-96142D01*
X89731Y-96113D01*
X89713Y-96084D01*
X89694Y-96044D01*
X89676Y-96004D01*
X89654Y-95956D01*
X89636Y-95905D01*
X89618Y-95851D01*
X89600Y-95793D01*
X89585Y-95731D01*
X89578Y-95665D01*
X89571Y-95596D01*
X89567Y-95523D01*
Y-95483D01*
X89571Y-95454D01*
Y-95421D01*
X89574Y-95381D01*
X89582Y-95337D01*
X89589Y-95287D01*
X89607Y-95181D01*
X89636Y-95072D01*
X89676Y-94963D01*
X89702Y-94912D01*
X89731Y-94861D01*
X89734Y-94857D01*
X89738Y-94850D01*
X89749Y-94835D01*
X89763Y-94821D01*
X89778Y-94799D01*
X89800Y-94773D01*
X89825Y-94744D01*
X89855Y-94715D01*
X89887Y-94686D01*
X89920Y-94653D01*
X90004Y-94588D01*
X90102Y-94526D01*
X90211Y-94471D01*
X90215D01*
X90226Y-94464D01*
X90244Y-94460D01*
X90266Y-94449D01*
X90295Y-94442D01*
X90331Y-94431D01*
X90371Y-94417D01*
X90415Y-94406D01*
X90462Y-94395D01*
X90517Y-94380D01*
X90630Y-94362D01*
X90757Y-94347D01*
X90888Y-94340D01*
X90892D01*
X90906D01*
X90928D01*
X90954Y-94344D01*
D02*
G37*
G36*
X90855Y-96841D02*
X90906D01*
X90965Y-96844D01*
X91034Y-96852D01*
X91110Y-96859D01*
X91194Y-96870D01*
X91278Y-96885D01*
X91369Y-96903D01*
X91456Y-96925D01*
X91543Y-96950D01*
X91627Y-96983D01*
X91707Y-97019D01*
X91784Y-97059D01*
X91849Y-97106D01*
X91853Y-97110D01*
X91860Y-97117D01*
X91875Y-97132D01*
X91896Y-97150D01*
X91918Y-97172D01*
X91940Y-97201D01*
X91969Y-97238D01*
X91995Y-97274D01*
X92020Y-97318D01*
X92049Y-97365D01*
X92071Y-97420D01*
X92097Y-97474D01*
X92115Y-97536D01*
X92129Y-97602D01*
X92137Y-97671D01*
X92140Y-97743D01*
Y-97773D01*
X92137Y-97795D01*
Y-97820D01*
X92133Y-97849D01*
X92119Y-97918D01*
X92100Y-97995D01*
X92071Y-98075D01*
X92027Y-98155D01*
X92002Y-98195D01*
X91973Y-98231D01*
X91969Y-98235D01*
X91966Y-98239D01*
X91955Y-98250D01*
X91944Y-98260D01*
X91926Y-98279D01*
X91904Y-98293D01*
X91853Y-98333D01*
X91787Y-98373D01*
X91707Y-98410D01*
X91616Y-98442D01*
X91514Y-98464D01*
X91489Y-98155D01*
X91492D01*
X91496Y-98151D01*
X91518Y-98148D01*
X91551Y-98137D01*
X91591Y-98122D01*
X91634Y-98107D01*
X91678Y-98086D01*
X91718Y-98060D01*
X91751Y-98035D01*
X91758Y-98027D01*
X91773Y-98013D01*
X91795Y-97987D01*
X91820Y-97951D01*
X91842Y-97904D01*
X91864Y-97853D01*
X91878Y-97791D01*
X91886Y-97725D01*
Y-97700D01*
X91882Y-97671D01*
X91875Y-97638D01*
X91864Y-97594D01*
X91849Y-97551D01*
X91831Y-97507D01*
X91802Y-97463D01*
X91798Y-97456D01*
X91784Y-97438D01*
X91758Y-97412D01*
X91722Y-97379D01*
X91678Y-97343D01*
X91627Y-97303D01*
X91562Y-97267D01*
X91489Y-97230D01*
X91485D01*
X91478Y-97227D01*
X91467Y-97223D01*
X91452Y-97216D01*
X91431Y-97212D01*
X91405Y-97205D01*
X91376Y-97198D01*
X91340Y-97190D01*
X91299Y-97179D01*
X91256Y-97172D01*
X91209Y-97165D01*
X91158Y-97161D01*
X91099Y-97154D01*
X91041Y-97150D01*
X90976Y-97147D01*
X90910D01*
X90914Y-97150D01*
X90936Y-97165D01*
X90965Y-97190D01*
X91001Y-97223D01*
X91045Y-97259D01*
X91085Y-97307D01*
X91125Y-97358D01*
X91161Y-97416D01*
Y-97420D01*
X91165Y-97423D01*
X91176Y-97445D01*
X91187Y-97478D01*
X91205Y-97522D01*
X91220Y-97572D01*
X91230Y-97631D01*
X91241Y-97693D01*
X91245Y-97758D01*
Y-97787D01*
X91241Y-97809D01*
X91238Y-97838D01*
X91234Y-97867D01*
X91227Y-97904D01*
X91216Y-97940D01*
X91190Y-98024D01*
X91172Y-98067D01*
X91147Y-98111D01*
X91121Y-98155D01*
X91092Y-98202D01*
X91056Y-98246D01*
X91016Y-98286D01*
X91012Y-98290D01*
X91005Y-98297D01*
X90994Y-98308D01*
X90976Y-98319D01*
X90950Y-98337D01*
X90925Y-98355D01*
X90892Y-98373D01*
X90855Y-98395D01*
X90815Y-98417D01*
X90772Y-98435D01*
X90721Y-98453D01*
X90670Y-98471D01*
X90615Y-98482D01*
X90553Y-98493D01*
X90491Y-98501D01*
X90426Y-98504D01*
X90422D01*
X90415D01*
X90404D01*
X90386D01*
X90364Y-98501D01*
X90342D01*
X90284Y-98490D01*
X90215Y-98479D01*
X90142Y-98461D01*
X90062Y-98435D01*
X89986Y-98399D01*
X89982D01*
X89978Y-98395D01*
X89967Y-98388D01*
X89953Y-98381D01*
X89916Y-98359D01*
X89869Y-98326D01*
X89818Y-98286D01*
X89767Y-98239D01*
X89716Y-98180D01*
X89672Y-98118D01*
Y-98115D01*
X89669Y-98111D01*
X89662Y-98100D01*
X89658Y-98086D01*
X89640Y-98049D01*
X89622Y-98002D01*
X89600Y-97940D01*
X89585Y-97871D01*
X89571Y-97795D01*
X89567Y-97711D01*
Y-97693D01*
X89571Y-97674D01*
Y-97645D01*
X89574Y-97613D01*
X89582Y-97576D01*
X89592Y-97532D01*
X89603Y-97489D01*
X89618Y-97438D01*
X89636Y-97387D01*
X89658Y-97336D01*
X89687Y-97281D01*
X89720Y-97230D01*
X89756Y-97179D01*
X89800Y-97128D01*
X89851Y-97081D01*
X89855Y-97077D01*
X89865Y-97070D01*
X89880Y-97059D01*
X89905Y-97045D01*
X89938Y-97023D01*
X89975Y-97005D01*
X90022Y-96983D01*
X90073Y-96961D01*
X90135Y-96935D01*
X90204Y-96914D01*
X90280Y-96895D01*
X90364Y-96877D01*
X90459Y-96859D01*
X90561Y-96848D01*
X90670Y-96841D01*
X90786Y-96837D01*
X90790D01*
X90794D01*
X90804D01*
X90819D01*
X90855Y-96841D01*
D02*
G37*
G36*
X90965Y-98814D02*
X91008D01*
X91056Y-98817D01*
X91110Y-98821D01*
X91223Y-98832D01*
X91343Y-98850D01*
X91463Y-98872D01*
X91518Y-98887D01*
X91573Y-98901D01*
X91576D01*
X91584Y-98905D01*
X91598Y-98912D01*
X91616Y-98919D01*
X91642Y-98927D01*
X91667Y-98941D01*
X91729Y-98970D01*
X91795Y-99007D01*
X91864Y-99054D01*
X91933Y-99108D01*
X91991Y-99174D01*
Y-99178D01*
X91998Y-99181D01*
X92006Y-99192D01*
X92013Y-99207D01*
X92027Y-99225D01*
X92039Y-99247D01*
X92068Y-99301D01*
X92093Y-99367D01*
X92119Y-99443D01*
X92133Y-99534D01*
X92140Y-99633D01*
Y-99665D01*
X92137Y-99705D01*
X92129Y-99753D01*
X92119Y-99807D01*
X92104Y-99866D01*
X92086Y-99928D01*
X92057Y-99986D01*
Y-99989D01*
X92053Y-99993D01*
X92042Y-100011D01*
X92024Y-100040D01*
X91998Y-100077D01*
X91962Y-100117D01*
X91922Y-100161D01*
X91875Y-100200D01*
X91820Y-100241D01*
X91813Y-100244D01*
X91795Y-100259D01*
X91762Y-100273D01*
X91715Y-100299D01*
X91660Y-100321D01*
X91598Y-100350D01*
X91525Y-100375D01*
X91445Y-100397D01*
X91442D01*
X91434Y-100401D01*
X91423Y-100404D01*
X91405Y-100408D01*
X91383Y-100412D01*
X91358Y-100415D01*
X91325Y-100423D01*
X91289Y-100426D01*
X91249Y-100434D01*
X91205Y-100437D01*
X91154Y-100441D01*
X91103Y-100448D01*
X91045Y-100452D01*
X90987D01*
X90921Y-100455D01*
X90852D01*
X90848D01*
X90834D01*
X90808D01*
X90779D01*
X90739Y-100452D01*
X90695D01*
X90648Y-100448D01*
X90597Y-100444D01*
X90481Y-100434D01*
X90360Y-100415D01*
X90244Y-100393D01*
X90189Y-100379D01*
X90135Y-100361D01*
X90131D01*
X90124Y-100357D01*
X90109Y-100350D01*
X90091Y-100343D01*
X90066Y-100335D01*
X90040Y-100321D01*
X89978Y-100292D01*
X89913Y-100255D01*
X89840Y-100208D01*
X89774Y-100153D01*
X89713Y-100088D01*
Y-100084D01*
X89705Y-100080D01*
X89698Y-100069D01*
X89691Y-100055D01*
X89680Y-100037D01*
X89665Y-100019D01*
X89640Y-99964D01*
X89614Y-99898D01*
X89589Y-99822D01*
X89574Y-99731D01*
X89567Y-99633D01*
Y-99596D01*
X89571Y-99571D01*
X89574Y-99542D01*
X89582Y-99505D01*
X89589Y-99465D01*
X89600Y-99422D01*
X89614Y-99378D01*
X89629Y-99331D01*
X89651Y-99283D01*
X89676Y-99236D01*
X89705Y-99189D01*
X89742Y-99141D01*
X89782Y-99098D01*
X89825Y-99058D01*
X89829Y-99054D01*
X89840Y-99047D01*
X89858Y-99036D01*
X89887Y-99018D01*
X89920Y-98999D01*
X89964Y-98981D01*
X90015Y-98956D01*
X90073Y-98934D01*
X90138Y-98912D01*
X90215Y-98890D01*
X90299Y-98868D01*
X90393Y-98850D01*
X90495Y-98832D01*
X90604Y-98821D01*
X90724Y-98814D01*
X90852Y-98810D01*
X90855D01*
X90870D01*
X90895D01*
X90925D01*
X90965Y-98814D01*
D02*
G37*
G36*
X124418Y-76037D02*
X124455D01*
X124491Y-76040D01*
X124538Y-76044D01*
X124586Y-76051D01*
X124691Y-76069D01*
X124808Y-76095D01*
X124924Y-76131D01*
X125037Y-76182D01*
X125041Y-76186D01*
X125052Y-76190D01*
X125066Y-76197D01*
X125084Y-76211D01*
X125110Y-76226D01*
X125139Y-76244D01*
X125205Y-76292D01*
X125277Y-76353D01*
X125350Y-76426D01*
X125423Y-76510D01*
X125485Y-76608D01*
X125488Y-76612D01*
X125492Y-76623D01*
X125499Y-76637D01*
X125510Y-76656D01*
X125521Y-76685D01*
X125532Y-76714D01*
X125547Y-76750D01*
X125561Y-76790D01*
X125576Y-76834D01*
X125590Y-76881D01*
X125612Y-76983D01*
X125630Y-77100D01*
X125638Y-77220D01*
Y-77256D01*
X125634Y-77282D01*
X125630Y-77314D01*
X125627Y-77354D01*
X125623Y-77394D01*
X125612Y-77442D01*
X125590Y-77540D01*
X125558Y-77649D01*
X125536Y-77704D01*
X125510Y-77755D01*
X125478Y-77806D01*
X125445Y-77857D01*
X125441Y-77860D01*
X125437Y-77868D01*
X125427Y-77882D01*
X125408Y-77900D01*
X125390Y-77919D01*
X125365Y-77944D01*
X125336Y-77969D01*
X125306Y-77999D01*
X125270Y-78028D01*
X125226Y-78057D01*
X125183Y-78090D01*
X125135Y-78119D01*
X125081Y-78144D01*
X125026Y-78173D01*
X124968Y-78195D01*
X124902Y-78217D01*
X124826Y-77889D01*
X124830D01*
X124837Y-77886D01*
X124852Y-77878D01*
X124870Y-77871D01*
X124891Y-77864D01*
X124921Y-77853D01*
X124979Y-77824D01*
X125044Y-77788D01*
X125110Y-77744D01*
X125172Y-77689D01*
X125226Y-77631D01*
X125234Y-77624D01*
X125248Y-77602D01*
X125266Y-77565D01*
X125292Y-77518D01*
X125314Y-77456D01*
X125336Y-77387D01*
X125350Y-77303D01*
X125354Y-77212D01*
Y-77183D01*
X125350Y-77165D01*
Y-77140D01*
X125347Y-77110D01*
X125336Y-77041D01*
X125321Y-76965D01*
X125295Y-76885D01*
X125259Y-76801D01*
X125212Y-76725D01*
Y-76721D01*
X125205Y-76717D01*
X125186Y-76692D01*
X125157Y-76659D01*
X125113Y-76619D01*
X125059Y-76572D01*
X124997Y-76528D01*
X124921Y-76488D01*
X124837Y-76452D01*
X124833D01*
X124826Y-76448D01*
X124815Y-76444D01*
X124797Y-76441D01*
X124775Y-76433D01*
X124750Y-76426D01*
X124688Y-76415D01*
X124615Y-76401D01*
X124535Y-76386D01*
X124447Y-76379D01*
X124353Y-76375D01*
X124349D01*
X124338D01*
X124320D01*
X124298D01*
X124273Y-76379D01*
X124240D01*
X124204Y-76382D01*
X124163Y-76386D01*
X124076Y-76397D01*
X123981Y-76415D01*
X123887Y-76437D01*
X123792Y-76466D01*
X123789D01*
X123781Y-76470D01*
X123770Y-76477D01*
X123752Y-76484D01*
X123708Y-76506D01*
X123658Y-76539D01*
X123599Y-76579D01*
X123537Y-76630D01*
X123483Y-76688D01*
X123432Y-76757D01*
Y-76761D01*
X123428Y-76768D01*
X123421Y-76779D01*
X123414Y-76794D01*
X123406Y-76812D01*
X123396Y-76834D01*
X123374Y-76885D01*
X123352Y-76950D01*
X123334Y-77023D01*
X123319Y-77103D01*
X123315Y-77187D01*
Y-77212D01*
X123319Y-77234D01*
Y-77260D01*
X123323Y-77285D01*
X123337Y-77351D01*
X123355Y-77427D01*
X123384Y-77504D01*
X123425Y-77584D01*
X123446Y-77624D01*
X123476Y-77660D01*
X123479Y-77664D01*
X123483Y-77667D01*
X123494Y-77678D01*
X123505Y-77693D01*
X123523Y-77707D01*
X123545Y-77726D01*
X123566Y-77747D01*
X123596Y-77766D01*
X123628Y-77788D01*
X123665Y-77813D01*
X123701Y-77835D01*
X123745Y-77857D01*
X123792Y-77875D01*
X123843Y-77893D01*
X123898Y-77911D01*
X123956Y-77926D01*
X123872Y-78261D01*
X123869D01*
X123854Y-78257D01*
X123832Y-78250D01*
X123803Y-78239D01*
X123770Y-78228D01*
X123730Y-78213D01*
X123687Y-78195D01*
X123639Y-78173D01*
X123537Y-78122D01*
X123435Y-78057D01*
X123384Y-78017D01*
X123334Y-77977D01*
X123290Y-77933D01*
X123246Y-77882D01*
X123243Y-77878D01*
X123235Y-77871D01*
X123228Y-77853D01*
X123214Y-77835D01*
X123195Y-77806D01*
X123177Y-77777D01*
X123159Y-77737D01*
X123141Y-77697D01*
X123119Y-77649D01*
X123101Y-77598D01*
X123082Y-77544D01*
X123064Y-77485D01*
X123050Y-77424D01*
X123042Y-77358D01*
X123035Y-77289D01*
X123031Y-77216D01*
Y-77176D01*
X123035Y-77147D01*
Y-77114D01*
X123039Y-77074D01*
X123046Y-77030D01*
X123053Y-76979D01*
X123072Y-76874D01*
X123101Y-76765D01*
X123141Y-76656D01*
X123166Y-76604D01*
X123195Y-76554D01*
X123199Y-76550D01*
X123203Y-76543D01*
X123214Y-76528D01*
X123228Y-76513D01*
X123243Y-76492D01*
X123264Y-76466D01*
X123290Y-76437D01*
X123319Y-76408D01*
X123352Y-76379D01*
X123384Y-76346D01*
X123468Y-76281D01*
X123566Y-76219D01*
X123676Y-76164D01*
X123679D01*
X123690Y-76157D01*
X123708Y-76153D01*
X123730Y-76142D01*
X123759Y-76135D01*
X123796Y-76124D01*
X123836Y-76109D01*
X123880Y-76099D01*
X123927Y-76088D01*
X123981Y-76073D01*
X124094Y-76055D01*
X124222Y-76040D01*
X124353Y-76033D01*
X124356D01*
X124371D01*
X124393D01*
X124418Y-76037D01*
D02*
G37*
G36*
X123759Y-78869D02*
X123756D01*
X123749D01*
X123738Y-78872D01*
X123719Y-78876D01*
X123679Y-78887D01*
X123625Y-78901D01*
X123570Y-78923D01*
X123508Y-78952D01*
X123454Y-78989D01*
X123403Y-79032D01*
X123399Y-79040D01*
X123384Y-79054D01*
X123366Y-79083D01*
X123345Y-79123D01*
X123323Y-79167D01*
X123304Y-79222D01*
X123290Y-79284D01*
X123286Y-79353D01*
Y-79375D01*
X123290Y-79389D01*
X123293Y-79433D01*
X123308Y-79484D01*
X123326Y-79546D01*
X123355Y-79607D01*
X123399Y-79673D01*
X123425Y-79702D01*
X123454Y-79731D01*
X123457Y-79735D01*
X123461Y-79739D01*
X123472Y-79746D01*
X123483Y-79757D01*
X123523Y-79782D01*
X123574Y-79811D01*
X123636Y-79837D01*
X123712Y-79862D01*
X123803Y-79880D01*
X123851Y-79888D01*
X123901D01*
X123905D01*
X123912D01*
X123927D01*
X123945Y-79884D01*
X123967D01*
X123992Y-79880D01*
X124051Y-79870D01*
X124120Y-79851D01*
X124189Y-79826D01*
X124255Y-79790D01*
X124316Y-79739D01*
X124320D01*
X124324Y-79731D01*
X124342Y-79713D01*
X124367Y-79680D01*
X124397Y-79637D01*
X124422Y-79578D01*
X124447Y-79513D01*
X124466Y-79436D01*
X124473Y-79393D01*
Y-79324D01*
X124469Y-79295D01*
X124466Y-79258D01*
X124455Y-79214D01*
X124444Y-79171D01*
X124426Y-79123D01*
X124404Y-79076D01*
X124400Y-79072D01*
X124393Y-79058D01*
X124375Y-79036D01*
X124356Y-79007D01*
X124331Y-78978D01*
X124298Y-78949D01*
X124265Y-78916D01*
X124225Y-78890D01*
X124265Y-78599D01*
X125561Y-78843D01*
Y-80095D01*
X125266D01*
Y-79087D01*
X124586Y-78952D01*
X124589Y-78956D01*
X124593Y-78963D01*
X124600Y-78974D01*
X124611Y-78992D01*
X124622Y-79014D01*
X124637Y-79040D01*
X124666Y-79098D01*
X124695Y-79171D01*
X124720Y-79251D01*
X124739Y-79338D01*
X124746Y-79382D01*
Y-79462D01*
X124742Y-79484D01*
X124739Y-79513D01*
X124735Y-79546D01*
X124728Y-79582D01*
X124717Y-79622D01*
X124691Y-79709D01*
X124673Y-79757D01*
X124648Y-79804D01*
X124622Y-79851D01*
X124593Y-79899D01*
X124557Y-79942D01*
X124517Y-79986D01*
X124513Y-79990D01*
X124506Y-79997D01*
X124495Y-80008D01*
X124477Y-80023D01*
X124451Y-80041D01*
X124426Y-80059D01*
X124393Y-80081D01*
X124356Y-80103D01*
X124316Y-80121D01*
X124273Y-80143D01*
X124222Y-80161D01*
X124171Y-80179D01*
X124116Y-80194D01*
X124054Y-80204D01*
X123992Y-80212D01*
X123927Y-80215D01*
X123923D01*
X123912D01*
X123894D01*
X123869Y-80212D01*
X123839Y-80208D01*
X123807Y-80204D01*
X123767Y-80197D01*
X123727Y-80190D01*
X123632Y-80168D01*
X123534Y-80132D01*
X123483Y-80110D01*
X123435Y-80081D01*
X123384Y-80052D01*
X123337Y-80015D01*
X123334Y-80012D01*
X123323Y-80004D01*
X123308Y-79990D01*
X123290Y-79971D01*
X123268Y-79946D01*
X123239Y-79917D01*
X123214Y-79880D01*
X123184Y-79840D01*
X123155Y-79797D01*
X123130Y-79746D01*
X123104Y-79691D01*
X123079Y-79633D01*
X123061Y-79571D01*
X123046Y-79502D01*
X123035Y-79429D01*
X123031Y-79353D01*
Y-79320D01*
X123035Y-79295D01*
X123039Y-79265D01*
X123042Y-79233D01*
X123046Y-79193D01*
X123057Y-79153D01*
X123079Y-79062D01*
X123111Y-78970D01*
X123133Y-78923D01*
X123159Y-78876D01*
X123188Y-78832D01*
X123221Y-78789D01*
X123224Y-78785D01*
X123228Y-78778D01*
X123243Y-78770D01*
X123257Y-78756D01*
X123275Y-78738D01*
X123297Y-78719D01*
X123326Y-78698D01*
X123359Y-78679D01*
X123392Y-78658D01*
X123432Y-78636D01*
X123519Y-78596D01*
X123621Y-78563D01*
X123676Y-78552D01*
X123734Y-78545D01*
X123759Y-78869D01*
D02*
G37*
G36*
X123839Y-80503D02*
X123861D01*
X123887Y-80507D01*
X123945Y-80514D01*
X124011Y-80528D01*
X124076Y-80550D01*
X124145Y-80583D01*
X124211Y-80623D01*
X124214D01*
X124218Y-80630D01*
X124236Y-80645D01*
X124265Y-80674D01*
X124302Y-80714D01*
X124338Y-80765D01*
X124378Y-80827D01*
X124411Y-80896D01*
X124436Y-80980D01*
Y-80976D01*
X124440Y-80972D01*
X124444Y-80962D01*
X124451Y-80947D01*
X124466Y-80914D01*
X124487Y-80871D01*
X124517Y-80823D01*
X124553Y-80776D01*
X124593Y-80732D01*
X124637Y-80692D01*
X124644Y-80689D01*
X124659Y-80678D01*
X124688Y-80663D01*
X124724Y-80649D01*
X124771Y-80630D01*
X124826Y-80616D01*
X124888Y-80605D01*
X124953Y-80601D01*
X124957D01*
X124964D01*
X124979D01*
X125001Y-80605D01*
X125022Y-80608D01*
X125052Y-80612D01*
X125113Y-80627D01*
X125186Y-80649D01*
X125263Y-80685D01*
X125303Y-80707D01*
X125343Y-80732D01*
X125379Y-80765D01*
X125416Y-80798D01*
X125419Y-80801D01*
X125423Y-80809D01*
X125434Y-80820D01*
X125445Y-80834D01*
X125459Y-80852D01*
X125474Y-80878D01*
X125492Y-80907D01*
X125510Y-80936D01*
X125529Y-80972D01*
X125547Y-81013D01*
X125561Y-81056D01*
X125576Y-81104D01*
X125598Y-81205D01*
X125601Y-81264D01*
X125605Y-81322D01*
Y-81355D01*
X125601Y-81377D01*
X125598Y-81406D01*
X125594Y-81438D01*
X125590Y-81475D01*
X125580Y-81511D01*
X125558Y-81599D01*
X125525Y-81686D01*
X125503Y-81730D01*
X125478Y-81773D01*
X125445Y-81813D01*
X125412Y-81853D01*
X125408Y-81857D01*
X125405Y-81861D01*
X125394Y-81872D01*
X125379Y-81886D01*
X125357Y-81901D01*
X125336Y-81919D01*
X125281Y-81955D01*
X125212Y-81992D01*
X125132Y-82025D01*
X125041Y-82050D01*
X124993Y-82054D01*
X124943Y-82057D01*
X124939D01*
X124935D01*
X124913D01*
X124881Y-82054D01*
X124840Y-82046D01*
X124790Y-82035D01*
X124739Y-82017D01*
X124688Y-81995D01*
X124637Y-81963D01*
X124629Y-81959D01*
X124615Y-81944D01*
X124593Y-81923D01*
X124564Y-81893D01*
X124531Y-81853D01*
X124498Y-81806D01*
X124466Y-81752D01*
X124436Y-81686D01*
Y-81690D01*
X124433Y-81697D01*
X124429Y-81708D01*
X124422Y-81722D01*
X124404Y-81766D01*
X124378Y-81817D01*
X124342Y-81872D01*
X124302Y-81930D01*
X124251Y-81984D01*
X124193Y-82035D01*
X124189D01*
X124185Y-82039D01*
X124163Y-82054D01*
X124127Y-82075D01*
X124080Y-82097D01*
X124021Y-82119D01*
X123952Y-82141D01*
X123876Y-82156D01*
X123792Y-82159D01*
X123789D01*
X123778D01*
X123759D01*
X123738Y-82156D01*
X123712Y-82152D01*
X123679Y-82148D01*
X123643Y-82141D01*
X123603Y-82130D01*
X123519Y-82105D01*
X123472Y-82086D01*
X123428Y-82061D01*
X123381Y-82035D01*
X123337Y-82006D01*
X123293Y-81970D01*
X123250Y-81930D01*
X123246Y-81926D01*
X123239Y-81919D01*
X123228Y-81908D01*
X123217Y-81890D01*
X123199Y-81864D01*
X123181Y-81839D01*
X123162Y-81806D01*
X123141Y-81770D01*
X123119Y-81730D01*
X123101Y-81682D01*
X123082Y-81631D01*
X123064Y-81580D01*
X123053Y-81522D01*
X123042Y-81460D01*
X123035Y-81398D01*
X123031Y-81329D01*
Y-81293D01*
X123035Y-81267D01*
X123039Y-81235D01*
X123042Y-81198D01*
X123050Y-81158D01*
X123061Y-81115D01*
X123086Y-81016D01*
X123104Y-80965D01*
X123123Y-80918D01*
X123148Y-80867D01*
X123177Y-80816D01*
X123210Y-80769D01*
X123250Y-80725D01*
X123254Y-80721D01*
X123261Y-80714D01*
X123272Y-80703D01*
X123290Y-80689D01*
X123312Y-80674D01*
X123337Y-80652D01*
X123366Y-80634D01*
X123403Y-80612D01*
X123439Y-80590D01*
X123483Y-80572D01*
X123574Y-80536D01*
X123628Y-80521D01*
X123683Y-80510D01*
X123741Y-80503D01*
X123800Y-80499D01*
X123803D01*
X123810D01*
X123825D01*
X123839Y-80503D01*
D02*
G37*
G36*
X491455Y-122282D02*
X491502Y-122290D01*
X491560Y-122300D01*
X491626Y-122319D01*
X491691Y-122340D01*
X491757Y-122370D01*
X491760D01*
X491764Y-122373D01*
X491786Y-122384D01*
X491819Y-122406D01*
X491855Y-122431D01*
X491899Y-122468D01*
X491943Y-122508D01*
X491986Y-122555D01*
X492023Y-122610D01*
X492026Y-122617D01*
X492037Y-122635D01*
X492052Y-122668D01*
X492070Y-122708D01*
X492088Y-122755D01*
X492103Y-122810D01*
X492114Y-122872D01*
X492117Y-122934D01*
Y-122941D01*
Y-122963D01*
X492114Y-122992D01*
X492106Y-123032D01*
X492095Y-123079D01*
X492077Y-123130D01*
X492055Y-123181D01*
X492026Y-123232D01*
X492023Y-123240D01*
X492012Y-123254D01*
X491990Y-123280D01*
X491961Y-123309D01*
X491924Y-123341D01*
X491881Y-123378D01*
X491830Y-123411D01*
X491768Y-123443D01*
X491771D01*
X491779Y-123447D01*
X491790Y-123451D01*
X491804Y-123454D01*
X491844Y-123469D01*
X491895Y-123491D01*
X491953Y-123520D01*
X492012Y-123556D01*
X492066Y-123603D01*
X492117Y-123658D01*
X492121Y-123665D01*
X492135Y-123687D01*
X492157Y-123724D01*
X492179Y-123771D01*
X492201Y-123829D01*
X492223Y-123898D01*
X492237Y-123978D01*
X492241Y-124066D01*
Y-124069D01*
Y-124080D01*
Y-124099D01*
X492237Y-124120D01*
X492234Y-124150D01*
X492226Y-124182D01*
X492219Y-124219D01*
X492212Y-124259D01*
X492183Y-124346D01*
X492161Y-124393D01*
X492139Y-124437D01*
X492110Y-124484D01*
X492077Y-124532D01*
X492041Y-124579D01*
X491997Y-124623D01*
X491994Y-124626D01*
X491986Y-124634D01*
X491972Y-124644D01*
X491953Y-124659D01*
X491932Y-124677D01*
X491902Y-124696D01*
X491870Y-124717D01*
X491830Y-124735D01*
X491790Y-124757D01*
X491742Y-124779D01*
X491695Y-124797D01*
X491640Y-124816D01*
X491582Y-124830D01*
X491520Y-124841D01*
X491458Y-124848D01*
X491389Y-124852D01*
X491357D01*
X491335Y-124848D01*
X491305Y-124845D01*
X491273Y-124841D01*
X491236Y-124834D01*
X491196Y-124827D01*
X491109Y-124805D01*
X491018Y-124768D01*
X490971Y-124747D01*
X490927Y-124721D01*
X490883Y-124688D01*
X490840Y-124655D01*
X490836Y-124652D01*
X490829Y-124644D01*
X490818Y-124634D01*
X490807Y-124619D01*
X490789Y-124601D01*
X490770Y-124575D01*
X490749Y-124550D01*
X490727Y-124517D01*
X490705Y-124481D01*
X490683Y-124444D01*
X490643Y-124357D01*
X490610Y-124255D01*
X490599Y-124200D01*
X490592Y-124142D01*
X490902Y-124102D01*
Y-124106D01*
X490905Y-124113D01*
X490909Y-124128D01*
X490912Y-124146D01*
X490916Y-124168D01*
X490923Y-124193D01*
X490941Y-124248D01*
X490967Y-124313D01*
X491000Y-124375D01*
X491036Y-124433D01*
X491080Y-124484D01*
X491087Y-124488D01*
X491102Y-124503D01*
X491131Y-124521D01*
X491167Y-124539D01*
X491211Y-124561D01*
X491265Y-124579D01*
X491327Y-124594D01*
X491393Y-124597D01*
X491415D01*
X491429Y-124594D01*
X491469Y-124590D01*
X491520Y-124579D01*
X491578Y-124561D01*
X491640Y-124535D01*
X491702Y-124499D01*
X491760Y-124448D01*
X491768Y-124441D01*
X491786Y-124419D01*
X491808Y-124386D01*
X491837Y-124342D01*
X491866Y-124288D01*
X491888Y-124226D01*
X491906Y-124153D01*
X491913Y-124073D01*
Y-124069D01*
Y-124062D01*
Y-124051D01*
X491910Y-124037D01*
X491906Y-123997D01*
X491895Y-123949D01*
X491881Y-123891D01*
X491855Y-123833D01*
X491819Y-123775D01*
X491771Y-123720D01*
X491764Y-123713D01*
X491746Y-123698D01*
X491717Y-123676D01*
X491677Y-123651D01*
X491626Y-123625D01*
X491564Y-123603D01*
X491495Y-123589D01*
X491418Y-123582D01*
X491386D01*
X491360Y-123585D01*
X491327Y-123589D01*
X491291Y-123596D01*
X491247Y-123603D01*
X491200Y-123614D01*
X491236Y-123341D01*
X491255D01*
X491269Y-123345D01*
X491316D01*
X491357Y-123338D01*
X491404Y-123330D01*
X491458Y-123320D01*
X491520Y-123301D01*
X491578Y-123276D01*
X491640Y-123243D01*
X491644D01*
X491648Y-123240D01*
X491666Y-123225D01*
X491691Y-123199D01*
X491720Y-123167D01*
X491750Y-123119D01*
X491775Y-123065D01*
X491793Y-123003D01*
X491800Y-122967D01*
Y-122926D01*
Y-122923D01*
Y-122919D01*
Y-122897D01*
X491793Y-122868D01*
X491786Y-122828D01*
X491771Y-122784D01*
X491753Y-122737D01*
X491724Y-122690D01*
X491684Y-122646D01*
X491680Y-122643D01*
X491662Y-122628D01*
X491637Y-122610D01*
X491604Y-122588D01*
X491560Y-122570D01*
X491509Y-122552D01*
X491451Y-122537D01*
X491386Y-122533D01*
X491357D01*
X491324Y-122541D01*
X491280Y-122548D01*
X491233Y-122563D01*
X491185Y-122581D01*
X491134Y-122610D01*
X491087Y-122646D01*
X491083Y-122650D01*
X491069Y-122668D01*
X491047Y-122694D01*
X491022Y-122730D01*
X490996Y-122777D01*
X490971Y-122836D01*
X490949Y-122905D01*
X490934Y-122985D01*
X490625Y-122930D01*
Y-122926D01*
X490628Y-122915D01*
X490632Y-122901D01*
X490636Y-122879D01*
X490643Y-122854D01*
X490654Y-122825D01*
X490676Y-122755D01*
X490712Y-122675D01*
X490756Y-122595D01*
X490810Y-122519D01*
X490880Y-122450D01*
X490883Y-122446D01*
X490891Y-122442D01*
X490902Y-122435D01*
X490916Y-122424D01*
X490934Y-122410D01*
X490960Y-122395D01*
X490985Y-122380D01*
X491018Y-122362D01*
X491091Y-122333D01*
X491175Y-122304D01*
X491273Y-122286D01*
X491324Y-122278D01*
X491415D01*
X491455Y-122282D01*
D02*
G37*
G36*
X488201Y-123746D02*
Y-123749D01*
Y-123764D01*
Y-123782D01*
Y-123807D01*
X488197Y-123840D01*
Y-123877D01*
X488193Y-123920D01*
X488190Y-123964D01*
X488179Y-124062D01*
X488164Y-124164D01*
X488142Y-124262D01*
X488128Y-124310D01*
X488113Y-124353D01*
Y-124357D01*
X488110Y-124364D01*
X488102Y-124375D01*
X488095Y-124390D01*
X488073Y-124430D01*
X488040Y-124481D01*
X487997Y-124539D01*
X487946Y-124597D01*
X487880Y-124659D01*
X487800Y-124714D01*
X487796D01*
X487789Y-124721D01*
X487778Y-124725D01*
X487760Y-124735D01*
X487738Y-124747D01*
X487709Y-124757D01*
X487680Y-124768D01*
X487644Y-124783D01*
X487604Y-124797D01*
X487560Y-124808D01*
X487513Y-124819D01*
X487458Y-124830D01*
X487403Y-124838D01*
X487345Y-124845D01*
X487214Y-124852D01*
X487181D01*
X487156Y-124848D01*
X487127D01*
X487090Y-124845D01*
X487050Y-124841D01*
X487010Y-124838D01*
X486919Y-124823D01*
X486821Y-124801D01*
X486726Y-124772D01*
X486635Y-124732D01*
X486632D01*
X486624Y-124725D01*
X486614Y-124717D01*
X486599Y-124710D01*
X486559Y-124681D01*
X486512Y-124641D01*
X486457Y-124590D01*
X486406Y-124532D01*
X486355Y-124459D01*
X486315Y-124379D01*
Y-124375D01*
X486311Y-124368D01*
X486308Y-124353D01*
X486301Y-124335D01*
X486293Y-124313D01*
X486286Y-124284D01*
X486275Y-124251D01*
X486268Y-124211D01*
X486261Y-124168D01*
X486249Y-124120D01*
X486242Y-124069D01*
X486235Y-124015D01*
X486228Y-123953D01*
X486224Y-123887D01*
X486220Y-123818D01*
Y-123746D01*
Y-122290D01*
X486555D01*
Y-123746D01*
Y-123749D01*
Y-123760D01*
Y-123778D01*
Y-123800D01*
X486559Y-123826D01*
Y-123858D01*
X486563Y-123927D01*
X486570Y-124007D01*
X486581Y-124088D01*
X486595Y-124164D01*
X486603Y-124197D01*
X486614Y-124230D01*
X486617Y-124237D01*
X486624Y-124255D01*
X486643Y-124281D01*
X486664Y-124317D01*
X486690Y-124353D01*
X486726Y-124393D01*
X486770Y-124433D01*
X486821Y-124466D01*
X486828Y-124470D01*
X486846Y-124481D01*
X486879Y-124492D01*
X486923Y-124506D01*
X486974Y-124524D01*
X487039Y-124535D01*
X487109Y-124546D01*
X487185Y-124550D01*
X487221D01*
X487243Y-124546D01*
X487276D01*
X487309Y-124543D01*
X487389Y-124528D01*
X487476Y-124510D01*
X487560Y-124481D01*
X487640Y-124441D01*
X487676Y-124415D01*
X487709Y-124386D01*
X487713Y-124382D01*
X487716Y-124379D01*
X487724Y-124368D01*
X487735Y-124353D01*
X487746Y-124331D01*
X487760Y-124310D01*
X487775Y-124277D01*
X487789Y-124244D01*
X487804Y-124204D01*
X487815Y-124157D01*
X487829Y-124102D01*
X487840Y-124044D01*
X487851Y-123978D01*
X487858Y-123909D01*
X487866Y-123829D01*
Y-123746D01*
Y-122290D01*
X488201D01*
Y-123746D01*
D02*
G37*
G36*
X489795Y-124808D02*
X489486D01*
Y-122839D01*
X489482Y-122843D01*
X489464Y-122857D01*
X489442Y-122879D01*
X489405Y-122905D01*
X489365Y-122937D01*
X489314Y-122974D01*
X489256Y-123014D01*
X489191Y-123054D01*
X489187D01*
X489183Y-123057D01*
X489161Y-123072D01*
X489125Y-123090D01*
X489081Y-123112D01*
X489031Y-123138D01*
X488976Y-123163D01*
X488921Y-123188D01*
X488867Y-123210D01*
Y-122912D01*
X488870D01*
X488878Y-122905D01*
X488892Y-122901D01*
X488910Y-122890D01*
X488932Y-122879D01*
X488958Y-122865D01*
X489020Y-122828D01*
X489092Y-122788D01*
X489165Y-122737D01*
X489242Y-122679D01*
X489318Y-122617D01*
X489322Y-122613D01*
X489325Y-122610D01*
X489336Y-122599D01*
X489351Y-122588D01*
X489384Y-122552D01*
X489427Y-122508D01*
X489471Y-122457D01*
X489518Y-122399D01*
X489558Y-122340D01*
X489595Y-122278D01*
X489795D01*
Y-124808D01*
D02*
G37*
G36*
X517728Y-124486D02*
Y-124490D01*
Y-124505D01*
Y-124523D01*
Y-124548D01*
X517725Y-124581D01*
Y-124618D01*
X517721Y-124661D01*
X517717Y-124705D01*
X517706Y-124803D01*
X517692Y-124905D01*
X517670Y-125003D01*
X517655Y-125051D01*
X517641Y-125094D01*
Y-125098D01*
X517637Y-125105D01*
X517630Y-125116D01*
X517623Y-125131D01*
X517601Y-125171D01*
X517568Y-125222D01*
X517524Y-125280D01*
X517473Y-125338D01*
X517408Y-125400D01*
X517328Y-125455D01*
X517324D01*
X517317Y-125462D01*
X517306Y-125466D01*
X517288Y-125477D01*
X517266Y-125487D01*
X517237Y-125498D01*
X517208Y-125509D01*
X517171Y-125524D01*
X517131Y-125539D01*
X517088Y-125549D01*
X517040Y-125560D01*
X516986Y-125571D01*
X516931Y-125578D01*
X516873Y-125586D01*
X516742Y-125593D01*
X516709D01*
X516683Y-125590D01*
X516654D01*
X516618Y-125586D01*
X516578Y-125582D01*
X516538Y-125578D01*
X516447Y-125564D01*
X516349Y-125542D01*
X516254Y-125513D01*
X516163Y-125473D01*
X516159D01*
X516152Y-125466D01*
X516141Y-125458D01*
X516127Y-125451D01*
X516086Y-125422D01*
X516039Y-125382D01*
X515985Y-125331D01*
X515934Y-125273D01*
X515883Y-125200D01*
X515843Y-125120D01*
Y-125116D01*
X515839Y-125109D01*
X515835Y-125094D01*
X515828Y-125076D01*
X515821Y-125054D01*
X515814Y-125025D01*
X515803Y-124993D01*
X515795Y-124952D01*
X515788Y-124909D01*
X515777Y-124861D01*
X515770Y-124811D01*
X515763Y-124756D01*
X515755Y-124694D01*
X515752Y-124628D01*
X515748Y-124559D01*
Y-124486D01*
Y-123030D01*
X516083D01*
Y-124486D01*
Y-124490D01*
Y-124501D01*
Y-124519D01*
Y-124541D01*
X516086Y-124567D01*
Y-124599D01*
X516090Y-124669D01*
X516097Y-124749D01*
X516108Y-124829D01*
X516123Y-124905D01*
X516130Y-124938D01*
X516141Y-124971D01*
X516145Y-124978D01*
X516152Y-124996D01*
X516170Y-125022D01*
X516192Y-125058D01*
X516218Y-125094D01*
X516254Y-125134D01*
X516298Y-125174D01*
X516349Y-125207D01*
X516356Y-125211D01*
X516374Y-125222D01*
X516407Y-125233D01*
X516451Y-125247D01*
X516502Y-125266D01*
X516567Y-125276D01*
X516636Y-125287D01*
X516713Y-125291D01*
X516749D01*
X516771Y-125287D01*
X516804D01*
X516836Y-125284D01*
X516917Y-125269D01*
X517004Y-125251D01*
X517088Y-125222D01*
X517168Y-125182D01*
X517204Y-125156D01*
X517237Y-125127D01*
X517240Y-125124D01*
X517244Y-125120D01*
X517251Y-125109D01*
X517262Y-125094D01*
X517273Y-125073D01*
X517288Y-125051D01*
X517302Y-125018D01*
X517317Y-124985D01*
X517331Y-124945D01*
X517342Y-124898D01*
X517357Y-124843D01*
X517368Y-124785D01*
X517379Y-124720D01*
X517386Y-124650D01*
X517393Y-124570D01*
Y-124486D01*
Y-123030D01*
X517728D01*
Y-124486D01*
D02*
G37*
G36*
X521416Y-124661D02*
X521758D01*
Y-124945D01*
X521416D01*
Y-125549D01*
X521106D01*
Y-124945D01*
X520011D01*
Y-124661D01*
X521164Y-123030D01*
X521416D01*
Y-124661D01*
D02*
G37*
G36*
X519322Y-125549D02*
X519013D01*
Y-123580D01*
X519009Y-123584D01*
X518991Y-123598D01*
X518969Y-123620D01*
X518933Y-123646D01*
X518893Y-123678D01*
X518842Y-123715D01*
X518784Y-123755D01*
X518718Y-123795D01*
X518715D01*
X518711Y-123799D01*
X518689Y-123813D01*
X518653Y-123831D01*
X518609Y-123853D01*
X518558Y-123879D01*
X518504Y-123904D01*
X518449Y-123930D01*
X518394Y-123951D01*
Y-123653D01*
X518398D01*
X518405Y-123646D01*
X518420Y-123642D01*
X518438Y-123631D01*
X518460Y-123620D01*
X518485Y-123606D01*
X518547Y-123569D01*
X518620Y-123529D01*
X518693Y-123478D01*
X518769Y-123420D01*
X518846Y-123358D01*
X518849Y-123354D01*
X518853Y-123351D01*
X518864Y-123340D01*
X518878Y-123329D01*
X518911Y-123293D01*
X518955Y-123249D01*
X518998Y-123198D01*
X519046Y-123140D01*
X519086Y-123082D01*
X519122Y-123020D01*
X519322D01*
Y-125549D01*
D02*
G37*
G36*
X462451Y-126171D02*
X460995D01*
X460992D01*
X460981D01*
X460963D01*
X460941D01*
X460915Y-126175D01*
X460883D01*
X460813Y-126178D01*
X460733Y-126186D01*
X460653Y-126197D01*
X460577Y-126211D01*
X460544Y-126218D01*
X460511Y-126229D01*
X460504Y-126233D01*
X460486Y-126240D01*
X460460Y-126259D01*
X460424Y-126280D01*
X460388Y-126306D01*
X460348Y-126342D01*
X460307Y-126386D01*
X460275Y-126437D01*
X460271Y-126444D01*
X460260Y-126462D01*
X460249Y-126495D01*
X460235Y-126539D01*
X460216Y-126590D01*
X460206Y-126655D01*
X460195Y-126724D01*
X460191Y-126801D01*
Y-126837D01*
X460195Y-126859D01*
Y-126892D01*
X460198Y-126925D01*
X460213Y-127005D01*
X460231Y-127092D01*
X460260Y-127176D01*
X460300Y-127256D01*
X460326Y-127292D01*
X460355Y-127325D01*
X460358Y-127329D01*
X460362Y-127332D01*
X460373Y-127340D01*
X460388Y-127350D01*
X460409Y-127361D01*
X460431Y-127376D01*
X460464Y-127391D01*
X460497Y-127405D01*
X460537Y-127420D01*
X460584Y-127430D01*
X460639Y-127445D01*
X460697Y-127456D01*
X460762Y-127467D01*
X460832Y-127474D01*
X460912Y-127481D01*
X460995D01*
X462451D01*
Y-127816D01*
X460995D01*
X460992D01*
X460977D01*
X460959D01*
X460933D01*
X460901Y-127813D01*
X460864D01*
X460821Y-127809D01*
X460777Y-127805D01*
X460679Y-127795D01*
X460577Y-127780D01*
X460478Y-127758D01*
X460431Y-127744D01*
X460388Y-127729D01*
X460384D01*
X460377Y-127725D01*
X460366Y-127718D01*
X460351Y-127711D01*
X460311Y-127689D01*
X460260Y-127656D01*
X460202Y-127613D01*
X460144Y-127562D01*
X460082Y-127496D01*
X460027Y-127416D01*
Y-127412D01*
X460020Y-127405D01*
X460016Y-127394D01*
X460005Y-127376D01*
X459994Y-127354D01*
X459983Y-127325D01*
X459972Y-127296D01*
X459958Y-127260D01*
X459943Y-127219D01*
X459933Y-127176D01*
X459922Y-127128D01*
X459911Y-127074D01*
X459903Y-127019D01*
X459896Y-126961D01*
X459889Y-126830D01*
Y-126797D01*
X459893Y-126772D01*
Y-126743D01*
X459896Y-126706D01*
X459900Y-126666D01*
X459903Y-126626D01*
X459918Y-126535D01*
X459940Y-126437D01*
X459969Y-126342D01*
X460009Y-126251D01*
Y-126248D01*
X460016Y-126240D01*
X460023Y-126229D01*
X460031Y-126215D01*
X460060Y-126175D01*
X460100Y-126127D01*
X460151Y-126073D01*
X460209Y-126022D01*
X460282Y-125971D01*
X460362Y-125931D01*
X460366D01*
X460373Y-125927D01*
X460388Y-125924D01*
X460406Y-125916D01*
X460428Y-125909D01*
X460457Y-125902D01*
X460489Y-125891D01*
X460529Y-125883D01*
X460573Y-125876D01*
X460620Y-125865D01*
X460671Y-125858D01*
X460726Y-125851D01*
X460788Y-125844D01*
X460853Y-125840D01*
X460923Y-125836D01*
X460995D01*
X462451D01*
Y-126171D01*
D02*
G37*
G36*
X462419Y-129899D02*
X462175D01*
X462171Y-129895D01*
X462164Y-129888D01*
X462149Y-129873D01*
X462127Y-129858D01*
X462102Y-129837D01*
X462073Y-129807D01*
X462036Y-129778D01*
X461993Y-129746D01*
X461949Y-129713D01*
X461898Y-129673D01*
X461840Y-129633D01*
X461782Y-129593D01*
X461716Y-129549D01*
X461647Y-129505D01*
X461571Y-129462D01*
X461494Y-129418D01*
X461490Y-129414D01*
X461476Y-129407D01*
X461454Y-129396D01*
X461421Y-129378D01*
X461381Y-129360D01*
X461338Y-129338D01*
X461287Y-129312D01*
X461228Y-129287D01*
X461163Y-129258D01*
X461097Y-129225D01*
X461025Y-129196D01*
X460948Y-129167D01*
X460791Y-129109D01*
X460624Y-129054D01*
X460620D01*
X460609Y-129050D01*
X460591Y-129047D01*
X460569Y-129039D01*
X460540Y-129032D01*
X460504Y-129025D01*
X460464Y-129014D01*
X460420Y-129007D01*
X460369Y-128996D01*
X460315Y-128985D01*
X460198Y-128967D01*
X460071Y-128948D01*
X459933Y-128937D01*
Y-128621D01*
X459936D01*
X459947D01*
X459962D01*
X459983Y-128624D01*
X460013D01*
X460049Y-128628D01*
X460089Y-128632D01*
X460133Y-128635D01*
X460184Y-128643D01*
X460235Y-128650D01*
X460296Y-128661D01*
X460358Y-128672D01*
X460424Y-128683D01*
X460497Y-128697D01*
X460646Y-128734D01*
X460650D01*
X460664Y-128737D01*
X460686Y-128745D01*
X460719Y-128755D01*
X460755Y-128766D01*
X460799Y-128781D01*
X460850Y-128796D01*
X460904Y-128817D01*
X460966Y-128839D01*
X461028Y-128861D01*
X461166Y-128916D01*
X461312Y-128981D01*
X461458Y-129054D01*
X461461Y-129058D01*
X461476Y-129065D01*
X461494Y-129076D01*
X461523Y-129090D01*
X461556Y-129109D01*
X461596Y-129134D01*
X461640Y-129159D01*
X461687Y-129189D01*
X461793Y-129258D01*
X461902Y-129331D01*
X462015Y-129414D01*
X462120Y-129502D01*
Y-128268D01*
X462419D01*
Y-129899D01*
D02*
G37*
%LPC*%
G36*
X671557Y-225819D02*
X671553D01*
X671539D01*
X671521D01*
X671491Y-225823D01*
X671459D01*
X671422Y-225827D01*
X671379Y-225830D01*
X671335Y-225834D01*
X671237Y-225852D01*
X671135Y-225874D01*
X671040Y-225907D01*
X670993Y-225928D01*
X670953Y-225950D01*
X670949D01*
X670942Y-225957D01*
X670931Y-225965D01*
X670916Y-225972D01*
X670880Y-226001D01*
X670836Y-226038D01*
X670789Y-226085D01*
X670742Y-226139D01*
X670702Y-226201D01*
X670669Y-226267D01*
X670665Y-226274D01*
X670662Y-226292D01*
X670651Y-226325D01*
X670640Y-226373D01*
X670633Y-226431D01*
X670622Y-226503D01*
X670618Y-226547D01*
Y-226594D01*
X670614Y-226642D01*
Y-227224D01*
X672536D01*
Y-226627D01*
X672533Y-226602D01*
X672529Y-226547D01*
X672525Y-226485D01*
X672518Y-226420D01*
X672507Y-226354D01*
X672493Y-226300D01*
X672489Y-226292D01*
X672485Y-226274D01*
X672474Y-226249D01*
X672460Y-226216D01*
X672438Y-226180D01*
X672416Y-226143D01*
X672391Y-226107D01*
X672362Y-226070D01*
X672354Y-226067D01*
X672340Y-226052D01*
X672314Y-226030D01*
X672278Y-226005D01*
X672230Y-225976D01*
X672176Y-225943D01*
X672114Y-225914D01*
X672045Y-225888D01*
X672041D01*
X672034Y-225885D01*
X672023Y-225881D01*
X672008Y-225877D01*
X671990Y-225874D01*
X671965Y-225867D01*
X671939Y-225859D01*
X671910Y-225852D01*
X671837Y-225841D01*
X671754Y-225830D01*
X671659Y-225823D01*
X671557Y-225819D01*
D02*
G37*
G36*
X675099Y-277106D02*
X673177D01*
Y-277703D01*
X673180Y-277729D01*
X673184Y-277783D01*
X673188Y-277845D01*
X673195Y-277911D01*
X673206Y-277976D01*
X673220Y-278031D01*
X673224Y-278038D01*
X673228Y-278057D01*
X673239Y-278082D01*
X673253Y-278115D01*
X673275Y-278151D01*
X673297Y-278188D01*
X673322Y-278224D01*
X673351Y-278260D01*
X673359Y-278264D01*
X673373Y-278279D01*
X673399Y-278300D01*
X673435Y-278326D01*
X673483Y-278355D01*
X673537Y-278388D01*
X673599Y-278417D01*
X673668Y-278442D01*
X673672D01*
X673679Y-278446D01*
X673690Y-278450D01*
X673705Y-278453D01*
X673723Y-278457D01*
X673748Y-278464D01*
X673774Y-278471D01*
X673803Y-278479D01*
X673876Y-278490D01*
X673959Y-278501D01*
X674054Y-278508D01*
X674156Y-278512D01*
X674160D01*
X674174D01*
X674192D01*
X674222Y-278508D01*
X674254D01*
X674291Y-278504D01*
X674334Y-278501D01*
X674378Y-278497D01*
X674476Y-278479D01*
X674578Y-278457D01*
X674673Y-278424D01*
X674720Y-278402D01*
X674760Y-278380D01*
X674764D01*
X674771Y-278373D01*
X674782Y-278366D01*
X674797Y-278359D01*
X674833Y-278329D01*
X674877Y-278293D01*
X674924Y-278246D01*
X674971Y-278191D01*
X675011Y-278129D01*
X675044Y-278064D01*
X675048Y-278057D01*
X675051Y-278038D01*
X675062Y-278006D01*
X675073Y-277958D01*
X675080Y-277900D01*
X675091Y-277827D01*
X675095Y-277783D01*
Y-277736D01*
X675099Y-277689D01*
Y-277106D01*
D02*
G37*
G36*
X674545Y-281460D02*
X674542D01*
X674535D01*
X674524D01*
X674505Y-281464D01*
X674483D01*
X674462Y-281467D01*
X674407Y-281478D01*
X674345Y-281496D01*
X674280Y-281518D01*
X674214Y-281555D01*
X674156Y-281602D01*
X674149Y-281609D01*
X674134Y-281627D01*
X674109Y-281660D01*
X674083Y-281700D01*
X674054Y-281755D01*
X674028Y-281817D01*
X674014Y-281886D01*
X674007Y-281962D01*
Y-281984D01*
X674010Y-281999D01*
X674014Y-282039D01*
X674025Y-282086D01*
X674043Y-282144D01*
X674069Y-282203D01*
X674105Y-282261D01*
X674156Y-282315D01*
X674163Y-282323D01*
X674185Y-282337D01*
X674218Y-282359D01*
X674265Y-282388D01*
X674323Y-282414D01*
X674393Y-282435D01*
X674476Y-282450D01*
X674571Y-282457D01*
X674575D01*
X674582D01*
X674596D01*
X674615Y-282454D01*
X674640D01*
X674665Y-282450D01*
X674724Y-282439D01*
X674793Y-282424D01*
X674866Y-282399D01*
X674935Y-282363D01*
X674997Y-282315D01*
X675000D01*
X675004Y-282308D01*
X675022Y-282290D01*
X675048Y-282261D01*
X675077Y-282221D01*
X675102Y-282170D01*
X675128Y-282112D01*
X675146Y-282046D01*
X675153Y-282010D01*
Y-281951D01*
X675150Y-281937D01*
X675146Y-281897D01*
X675132Y-281849D01*
X675113Y-281791D01*
X675080Y-281729D01*
X675040Y-281667D01*
X675011Y-281638D01*
X674982Y-281609D01*
X674979D01*
X674975Y-281602D01*
X674964Y-281595D01*
X674953Y-281587D01*
X674917Y-281562D01*
X674866Y-281536D01*
X674804Y-281507D01*
X674727Y-281482D01*
X674640Y-281467D01*
X674545Y-281460D01*
D02*
G37*
G36*
X32469Y15538D02*
X32466D01*
X32458D01*
X32444D01*
X32426Y15535D01*
X32400D01*
X32375Y15531D01*
X32316Y15520D01*
X32247Y15506D01*
X32175Y15480D01*
X32105Y15444D01*
X32043Y15396D01*
X32040D01*
X32036Y15389D01*
X32018Y15371D01*
X31993Y15342D01*
X31963Y15302D01*
X31938Y15251D01*
X31912Y15193D01*
X31894Y15127D01*
X31887Y15091D01*
Y15032D01*
X31891Y15018D01*
X31894Y14978D01*
X31909Y14931D01*
X31927Y14872D01*
X31960Y14810D01*
X32000Y14749D01*
X32029Y14719D01*
X32058Y14690D01*
X32062D01*
X32065Y14683D01*
X32076Y14676D01*
X32087Y14668D01*
X32124Y14643D01*
X32175Y14617D01*
X32236Y14588D01*
X32313Y14563D01*
X32400Y14548D01*
X32495Y14541D01*
X32498D01*
X32506D01*
X32517D01*
X32535Y14545D01*
X32557D01*
X32579Y14548D01*
X32633Y14559D01*
X32695Y14577D01*
X32761Y14599D01*
X32826Y14636D01*
X32884Y14683D01*
X32892Y14690D01*
X32906Y14708D01*
X32932Y14741D01*
X32957Y14781D01*
X32986Y14836D01*
X33012Y14898D01*
X33026Y14967D01*
X33034Y15043D01*
Y15065D01*
X33030Y15080D01*
X33026Y15120D01*
X33015Y15167D01*
X32997Y15225D01*
X32972Y15284D01*
X32935Y15342D01*
X32884Y15396D01*
X32877Y15404D01*
X32855Y15418D01*
X32822Y15440D01*
X32775Y15469D01*
X32717Y15495D01*
X32648Y15517D01*
X32564Y15531D01*
X32469Y15538D01*
D02*
G37*
G36*
X32884Y13551D02*
X32881D01*
X32866D01*
X32848D01*
X32819Y13547D01*
X32786D01*
X32750Y13544D01*
X32706Y13540D01*
X32662Y13536D01*
X32564Y13518D01*
X32462Y13496D01*
X32368Y13464D01*
X32320Y13442D01*
X32280Y13420D01*
X32276D01*
X32269Y13413D01*
X32258Y13405D01*
X32244Y13398D01*
X32207Y13369D01*
X32164Y13333D01*
X32116Y13285D01*
X32069Y13231D01*
X32029Y13169D01*
X31996Y13103D01*
X31993Y13096D01*
X31989Y13078D01*
X31978Y13045D01*
X31967Y12998D01*
X31960Y12939D01*
X31949Y12867D01*
X31945Y12823D01*
Y12776D01*
X31942Y12728D01*
Y12146D01*
X33863D01*
Y12743D01*
X33860Y12768D01*
X33856Y12823D01*
X33853Y12885D01*
X33845Y12950D01*
X33834Y13016D01*
X33820Y13070D01*
X33816Y13078D01*
X33813Y13096D01*
X33802Y13121D01*
X33787Y13154D01*
X33765Y13191D01*
X33743Y13227D01*
X33718Y13263D01*
X33689Y13300D01*
X33681Y13303D01*
X33667Y13318D01*
X33641Y13340D01*
X33605Y13365D01*
X33558Y13394D01*
X33503Y13427D01*
X33441Y13456D01*
X33372Y13482D01*
X33369D01*
X33361Y13485D01*
X33350Y13489D01*
X33336Y13493D01*
X33318Y13496D01*
X33292Y13504D01*
X33267Y13511D01*
X33237Y13518D01*
X33165Y13529D01*
X33081Y13540D01*
X32986Y13547D01*
X32884Y13551D01*
D02*
G37*
G36*
X25995Y13551D02*
X25991D01*
X25976D01*
X25958D01*
X25929Y13547D01*
X25896D01*
X25860Y13544D01*
X25816Y13540D01*
X25773Y13536D01*
X25674Y13518D01*
X25572Y13496D01*
X25478Y13464D01*
X25430Y13442D01*
X25390Y13420D01*
X25387D01*
X25379Y13413D01*
X25368Y13405D01*
X25354Y13398D01*
X25317Y13369D01*
X25274Y13333D01*
X25227Y13285D01*
X25179Y13231D01*
X25139Y13169D01*
X25106Y13103D01*
X25103Y13096D01*
X25099Y13078D01*
X25088Y13045D01*
X25077Y12998D01*
X25070Y12939D01*
X25059Y12867D01*
X25056Y12823D01*
Y12776D01*
X25052Y12728D01*
Y12146D01*
X26974D01*
Y12743D01*
X26970Y12768D01*
X26967Y12823D01*
X26963Y12885D01*
X26956Y12950D01*
X26945Y13016D01*
X26930Y13070D01*
X26926Y13078D01*
X26923Y13096D01*
X26912Y13121D01*
X26897Y13154D01*
X26875Y13191D01*
X26854Y13227D01*
X26828Y13263D01*
X26799Y13300D01*
X26792Y13303D01*
X26777Y13318D01*
X26752Y13340D01*
X26715Y13365D01*
X26668Y13394D01*
X26613Y13427D01*
X26551Y13456D01*
X26482Y13482D01*
X26479D01*
X26471Y13485D01*
X26460Y13489D01*
X26446Y13493D01*
X26428Y13496D01*
X26402Y13504D01*
X26377Y13511D01*
X26348Y13518D01*
X26275Y13529D01*
X26191Y13540D01*
X26096Y13547D01*
X25995Y13551D01*
D02*
G37*
G36*
X608523Y-22437D02*
X607729D01*
Y-23566D01*
X608523Y-22437D01*
D02*
G37*
G36*
X90426Y-97194D02*
X90419D01*
X90400D01*
X90368Y-97198D01*
X90328Y-97201D01*
X90280Y-97208D01*
X90229Y-97223D01*
X90175Y-97238D01*
X90120Y-97259D01*
X90113Y-97263D01*
X90095Y-97274D01*
X90069Y-97289D01*
X90036Y-97310D01*
X90004Y-97336D01*
X89964Y-97369D01*
X89931Y-97405D01*
X89898Y-97449D01*
X89894Y-97456D01*
X89887Y-97470D01*
X89873Y-97496D01*
X89862Y-97529D01*
X89847Y-97565D01*
X89833Y-97609D01*
X89825Y-97656D01*
X89822Y-97707D01*
Y-97725D01*
X89825Y-97740D01*
X89829Y-97776D01*
X89840Y-97824D01*
X89862Y-97875D01*
X89887Y-97933D01*
X89927Y-97991D01*
X89949Y-98020D01*
X89978Y-98046D01*
X89982D01*
X89986Y-98053D01*
X90007Y-98067D01*
X90044Y-98089D01*
X90091Y-98118D01*
X90153Y-98144D01*
X90226Y-98166D01*
X90310Y-98180D01*
X90408Y-98188D01*
X90411D01*
X90419D01*
X90433D01*
X90451Y-98184D01*
X90473D01*
X90499Y-98180D01*
X90557Y-98169D01*
X90623Y-98155D01*
X90692Y-98129D01*
X90757Y-98093D01*
X90819Y-98046D01*
X90826Y-98038D01*
X90845Y-98020D01*
X90866Y-97991D01*
X90895Y-97951D01*
X90925Y-97900D01*
X90947Y-97842D01*
X90965Y-97773D01*
X90972Y-97696D01*
Y-97674D01*
X90968Y-97660D01*
X90965Y-97623D01*
X90954Y-97572D01*
X90936Y-97518D01*
X90906Y-97456D01*
X90870Y-97398D01*
X90819Y-97339D01*
X90812Y-97332D01*
X90794Y-97318D01*
X90761Y-97292D01*
X90714Y-97267D01*
X90659Y-97241D01*
X90590Y-97216D01*
X90513Y-97201D01*
X90426Y-97194D01*
D02*
G37*
G36*
X90852Y-99127D02*
X90845D01*
X90826D01*
X90794D01*
X90750Y-99130D01*
X90703D01*
X90644Y-99134D01*
X90583Y-99138D01*
X90517Y-99145D01*
X90375Y-99163D01*
X90306Y-99174D01*
X90240Y-99189D01*
X90178Y-99203D01*
X90120Y-99225D01*
X90069Y-99247D01*
X90026Y-99272D01*
X90022D01*
X90018Y-99280D01*
X89993Y-99298D01*
X89960Y-99331D01*
X89924Y-99371D01*
X89887Y-99425D01*
X89855Y-99487D01*
X89829Y-99556D01*
X89825Y-99593D01*
X89822Y-99633D01*
Y-99655D01*
X89825Y-99669D01*
X89833Y-99705D01*
X89847Y-99756D01*
X89873Y-99811D01*
X89909Y-99873D01*
X89931Y-99902D01*
X89960Y-99931D01*
X89989Y-99960D01*
X90026Y-99989D01*
X90029D01*
X90036Y-99997D01*
X90047Y-100004D01*
X90066Y-100011D01*
X90091Y-100026D01*
X90124Y-100037D01*
X90160Y-100051D01*
X90204Y-100066D01*
X90259Y-100077D01*
X90317Y-100091D01*
X90386Y-100106D01*
X90459Y-100117D01*
X90546Y-100124D01*
X90637Y-100131D01*
X90739Y-100139D01*
X90852D01*
X90855D01*
X90859D01*
X90877D01*
X90910D01*
X90954Y-100135D01*
X91001D01*
X91059Y-100131D01*
X91121Y-100128D01*
X91190Y-100120D01*
X91329Y-100102D01*
X91398Y-100091D01*
X91463Y-100077D01*
X91525Y-100062D01*
X91584Y-100040D01*
X91634Y-100019D01*
X91678Y-99993D01*
X91682D01*
X91685Y-99986D01*
X91696Y-99979D01*
X91711Y-99968D01*
X91744Y-99935D01*
X91784Y-99895D01*
X91820Y-99840D01*
X91853Y-99778D01*
X91867Y-99746D01*
X91878Y-99709D01*
X91882Y-99669D01*
X91886Y-99629D01*
Y-99607D01*
X91882Y-99593D01*
X91875Y-99553D01*
X91864Y-99505D01*
X91842Y-99451D01*
X91809Y-99392D01*
X91787Y-99363D01*
X91765Y-99334D01*
X91736Y-99309D01*
X91704Y-99283D01*
X91700D01*
X91693Y-99276D01*
X91678Y-99269D01*
X91660Y-99258D01*
X91631Y-99247D01*
X91598Y-99232D01*
X91558Y-99221D01*
X91511Y-99207D01*
X91456Y-99192D01*
X91394Y-99178D01*
X91325Y-99163D01*
X91249Y-99152D01*
X91161Y-99141D01*
X91067Y-99134D01*
X90965Y-99130D01*
X90852Y-99127D01*
D02*
G37*
G36*
X124961Y-80918D02*
X124957D01*
X124953D01*
X124932Y-80922D01*
X124899Y-80925D01*
X124859Y-80932D01*
X124811Y-80947D01*
X124764Y-80965D01*
X124713Y-80994D01*
X124670Y-81031D01*
X124666Y-81034D01*
X124651Y-81053D01*
X124633Y-81078D01*
X124615Y-81111D01*
X124593Y-81155D01*
X124575Y-81205D01*
X124560Y-81264D01*
X124557Y-81329D01*
Y-81336D01*
X124560Y-81358D01*
X124564Y-81391D01*
X124571Y-81435D01*
X124586Y-81482D01*
X124604Y-81529D01*
X124633Y-81580D01*
X124670Y-81624D01*
X124673Y-81628D01*
X124691Y-81642D01*
X124713Y-81660D01*
X124746Y-81682D01*
X124786Y-81704D01*
X124833Y-81722D01*
X124888Y-81737D01*
X124946Y-81741D01*
X124950D01*
X124953D01*
X124975D01*
X125008Y-81733D01*
X125048Y-81726D01*
X125092Y-81711D01*
X125139Y-81690D01*
X125186Y-81660D01*
X125234Y-81620D01*
X125237Y-81617D01*
X125252Y-81599D01*
X125270Y-81573D01*
X125292Y-81540D01*
X125314Y-81497D01*
X125332Y-81449D01*
X125347Y-81391D01*
X125350Y-81329D01*
Y-81300D01*
X125343Y-81267D01*
X125336Y-81224D01*
X125321Y-81176D01*
X125303Y-81125D01*
X125274Y-81078D01*
X125234Y-81031D01*
X125230Y-81027D01*
X125215Y-81013D01*
X125190Y-80994D01*
X125157Y-80976D01*
X125117Y-80954D01*
X125070Y-80936D01*
X125019Y-80922D01*
X124961Y-80918D01*
D02*
G37*
G36*
X123800Y-80816D02*
X123792D01*
X123778D01*
X123752Y-80820D01*
X123719Y-80823D01*
X123679Y-80831D01*
X123636Y-80841D01*
X123592Y-80856D01*
X123545Y-80874D01*
X123541Y-80878D01*
X123523Y-80885D01*
X123501Y-80900D01*
X123476Y-80922D01*
X123443Y-80947D01*
X123410Y-80980D01*
X123381Y-81016D01*
X123352Y-81060D01*
X123348Y-81067D01*
X123341Y-81082D01*
X123330Y-81107D01*
X123319Y-81140D01*
X123308Y-81180D01*
X123297Y-81227D01*
X123290Y-81278D01*
X123286Y-81329D01*
Y-81351D01*
X123290Y-81366D01*
X123293Y-81409D01*
X123304Y-81460D01*
X123323Y-81519D01*
X123345Y-81580D01*
X123381Y-81639D01*
X123428Y-81697D01*
X123435Y-81704D01*
X123454Y-81719D01*
X123486Y-81744D01*
X123527Y-81770D01*
X123577Y-81795D01*
X123639Y-81821D01*
X123712Y-81835D01*
X123789Y-81842D01*
X123792D01*
X123800D01*
X123810D01*
X123825Y-81839D01*
X123865Y-81835D01*
X123920Y-81824D01*
X123974Y-81806D01*
X124036Y-81781D01*
X124098Y-81744D01*
X124156Y-81693D01*
X124163Y-81686D01*
X124178Y-81668D01*
X124204Y-81635D01*
X124233Y-81591D01*
X124258Y-81537D01*
X124284Y-81471D01*
X124298Y-81398D01*
X124305Y-81318D01*
Y-81296D01*
X124302Y-81282D01*
X124298Y-81242D01*
X124287Y-81191D01*
X124269Y-81133D01*
X124244Y-81074D01*
X124207Y-81013D01*
X124160Y-80958D01*
X124153Y-80951D01*
X124134Y-80936D01*
X124102Y-80914D01*
X124062Y-80889D01*
X124007Y-80860D01*
X123945Y-80838D01*
X123876Y-80823D01*
X123800Y-80816D01*
D02*
G37*
G36*
X521106Y-123533D02*
X520313Y-124661D01*
X521106D01*
Y-123533D01*
D02*
G37*
%LPD*%
D13*
X660138Y-244075D02*
X685532D01*
Y-211043D01*
X660138D02*
X685532D01*
X660138Y-244075D02*
Y-211043D01*
Y-260256D02*
X685532D01*
X660138Y-293287D02*
Y-260256D01*
Y-293287D02*
X685532D01*
Y-260256D01*
X38189Y6890D02*
X42520D01*
Y16732D01*
X38189D02*
X42520D01*
X38189Y6890D02*
Y16732D01*
X31299Y6890D02*
X35630D01*
Y16732D01*
X31299D02*
X35630D01*
X31299Y6890D02*
Y16732D01*
X24409Y6890D02*
X28740D01*
Y16732D01*
X24409D02*
X28740D01*
X24409Y6890D02*
Y16732D01*
X45079Y6890D02*
X49409D01*
Y16732D01*
X45079D02*
X49409D01*
X45079Y6890D02*
Y16732D01*
X80512Y-107677D02*
X84842D01*
X80512Y-118701D02*
Y-107677D01*
Y-118701D02*
X84842D01*
Y-107677D01*
X73425Y-120669D02*
X78150D01*
X73425Y-130118D02*
Y-120669D01*
Y-130118D02*
X78150D01*
Y-120669D01*
X653937Y-62155D02*
Y-55659D01*
X641339D02*
X653937D01*
X641339Y-62155D02*
Y-55659D01*
Y-62155D02*
X653937D01*
X619488Y-24754D02*
Y-18258D01*
X606890D02*
X619488D01*
X606890Y-24754D02*
Y-18258D01*
Y-24754D02*
X619488D01*
X86319Y-88041D02*
X92815D01*
X86319Y-100639D02*
Y-88041D01*
Y-100639D02*
X92815D01*
Y-88041D01*
X119783Y-69734D02*
X126279D01*
X119783Y-82332D02*
Y-69734D01*
Y-82332D02*
X126279D01*
Y-69734D01*
X477953Y-117569D02*
X494488D01*
Y-132135D02*
Y-117569D01*
X477953Y-132135D02*
X494488D01*
X477953D02*
Y-117569D01*
X508661Y-117765D02*
X522835D01*
Y-131939D02*
Y-117765D01*
X508661Y-131939D02*
X522835D01*
X508661D02*
Y-117765D01*
X454528Y-119201D02*
X466732D01*
X454528Y-132472D02*
Y-119201D01*
Y-132472D02*
X466732D01*
Y-119201D01*
M02*
